FILE_TYPE = MACRO_DRAWING;
SET COLOR_WIRE YELLOW;
SET COLOR_PROP MONO;
SET COLOR_DOT WHITE;
SET COLOR_ARC YELLOW;
SET COLOR_BODY GREEN;
SET COLOR_NOTE MONO;
SET PROP_DISPLAY VALUE;
SET PAGE_NUMBER P214;
FORCEADD RES..1
(-500 1050);
FORCEPROP 1 LASTPIN (-400 1050) $PN 2
J 0
(-438 1062);
DISPLAY 0.617021 (-438 1062);
PAINT WHITE (-438 1062);
FORCEPROP 1 LAST LOCATION R3D28
J 0
(-550 1100);
DISPLAY 0.617021 (-550 1100);
PAINT AQUA (-550 1100);
FORCEPROP 1 LASTPIN (-600 1050) $PN 1
J 0
(-588 1062);
DISPLAY 0.617021 (-588 1062);
PAINT WHITE (-588 1062);
FORCEPROP 1 LAST MATERIAL CHIP
J 0
(-450 925);
DISPLAY 0.617021 (-450 925);
PAINT SKYBLUE (-450 925);
FORCEPROP 1 LAST PACK_TYPE 0402
J 0
(-450 975);
DISPLAY 0.617021 (-450 975);
PAINT SKYBLUE (-450 975);
FORCEPROP 1 LAST PART_NUMBER G21796-017
J 0
(-650 875);
DISPLAY 0.617021 (-650 875);
PAINT BLUE (-650 875);
FORCEPROP 1 LAST VALUE 100.0
J 2
(-500 975);
DISPLAY 0.617021 (-500 975);
PAINT SKYBLUE (-500 975);
FORCEPROP 1 LAST WATTAGE 1/16W
J 2
(-475 925);
DISPLAY 0.617021 (-475 925);
PAINT SKYBLUE (-475 925);
FORCEPROP 1 LAST TOLERANCE 1%
J 0
(-675 975);
DISPLAY 0.617021 (-675 975);
PAINT SKYBLUE (-675 975);
FORCEPROP 2 LAST CDS_LIB mstr_discrete
J 0
(-500 1050);
PAINT ORANGE (-500 1050);
DISPLAY INVISIBLE (-500 1050);
FORCEPROP 2 LAST SEC_TYPE 0402
J 0
(-550 1246);
DISPLAY 1.021277 (-550 1246);
PAINT ORANGE (-550 1246);
DISPLAY INVISIBLE (-550 1246);
FORCEPROP 2 LAST CDS_LOCATION R3D28
J 0
(-550 1100);
DISPLAY 0.617021 (-550 1100);
PAINT AQUA (-550 1100);
DISPLAY INVISIBLE (-550 1100);
FORCEPROP 0 LAST BOM_COST PROC_VRD_VCCIO_CPU1
J 0
(-550 1150);
DISPLAY 0.723404 (-550 1150);
PAINT ORANGE (-550 1150);
DISPLAY INVISIBLE (-550 1150);
FORCEPROP 2 LAST SEC 1
J 0
(-550 1246);
DISPLAY 0.680851 (-550 1246);
PAINT MONO (-550 1246);
DISPLAY INVISIBLE (-550 1246);
FORCEPROP 1 LAST PATH I101
J 0
(-550 1200);
DISPLAY 0.978723 (-550 1200);
PAINT WHITE (-550 1200);
DISPLAY INVISIBLE (-550 1200);
FORCEPROP 2 LAST ROOM PVCCIO_CPU1
J 0
(-550 1200);
DISPLAY 0.723404 (-550 1200);
PAINT ORANGE (-550 1200);
DISPLAY INVISIBLE (-550 1200);
FORCEADD GND..1
(-250 825);
FORCEPROP 3 LASTPIN (-250 875) SIG_NAME GND\g
J 0
(-240 885);
DISPLAY 0.659574 (-240 885);
PAINT MONO (-240 885);
DISPLAY INVISIBLE (-240 885);
FORCEPROP 1 LAST HDL_POWER GND
J 0
(-250 975);
DISPLAY 0.638298 (-250 975);
PAINT GREEN (-250 975);
DISPLAY INVISIBLE (-250 975);
FORCEPROP 1 LAST BODY_TYPE PLUMBING
J 0
(-295 782);
DISPLAY 0.340426 (-295 782);
PAINT GREEN (-295 782);
DISPLAY INVISIBLE (-295 782);
FORCEPROP 1 LAST SIZE 1B
J 0
(-175 775);
DISPLAY 0.638298 (-175 775);
PAINT GREEN (-175 775);
DISPLAY INVISIBLE (-175 775);
FORCEPROP 2 LAST CDS_LIB mstr_symbols
J 0
(-250 825);
PAINT ORANGE (-250 825);
DISPLAY INVISIBLE (-250 825);
FORCEPROP 1 LAST PATH I102
J 0
(-175 825);
DISPLAY 0.872340 (-175 825);
PAINT AQUA (-175 825);
DISPLAY INVISIBLE (-175 825);
FORCEPROP 1 LAST VOLTAGE 0
J 0
(-250 825);
DISPLAY 0.723404 (-250 825);
PAINT SKYBLUE (-250 825);
DISPLAY INVISIBLE (-250 825);
FORCEPROP 2 LAST BOM_COST MEM_VRD_PVCCIO_CPU0
J 0
(-750 900);
DISPLAY 0.723404 (-750 900);
PAINT ORANGE (-750 900);
DISPLAY INVISIBLE (-750 900);
FORCEPROP 2 LAST ROOM PVCCIO_CPU0
J 0
(-550 900);
DISPLAY 0.723404 (-550 900);
PAINT ORANGE (-550 900);
DISPLAY INVISIBLE (-550 900);
FORCEADD OFFPAGE..2
(-25 1300);
FORCEPROP 2 LAST $XR0 213 
J 0
(164 1300);
DISPLAY 0.638298 (164 1300);
PAINT MONO (164 1300);
FORCEPROP 2 LAST PATH I103
J 0
(175 1350);
DISPLAY 1.021277 (175 1350);
PAINT ORANGE (175 1350);
DISPLAY INVISIBLE (175 1350);
FORCEPROP 1 LAST OFFPAGE TRUE
J 0
(300 1175);
DISPLAY 0.872340 (300 1175);
PAINT GREEN (300 1175);
DISPLAY INVISIBLE (300 1175);
FORCEPROP 2 LAST ROOM PVCCIO_CPU0
J 0
(250 1325);
DISPLAY 0.617021 (250 1325);
PAINT ORANGE (250 1325);
DISPLAY INVISIBLE (250 1325);
FORCEPROP 2 LAST CDS_LIB mstr_standard
J 0
(-25 1300);
PAINT ORANGE (-25 1300);
DISPLAY INVISIBLE (-25 1300);
FORCEPROP 1 LAST COMMENT_BODY TRUE
J 0
(-70 1205);
DISPLAY 0.872340 (-70 1205);
PAINT GREEN (-70 1205);
DISPLAY INVISIBLE (-70 1205);
FORCEADD RES..1
(-500 2250);
FORCEPROP 1 LASTPIN (-600 2250) $PN 1
J 0
(-588 2262);
DISPLAY 0.617021 (-588 2262);
PAINT WHITE (-588 2262);
FORCEPROP 1 LAST VALUE 100.0
J 2
(-500 2175);
DISPLAY 0.617021 (-500 2175);
PAINT SKYBLUE (-500 2175);
FORCEPROP 1 LAST TOLERANCE 1%
J 0
(-675 2175);
DISPLAY 0.617021 (-675 2175);
PAINT SKYBLUE (-675 2175);
FORCEPROP 1 LAST MATERIAL CHIP
J 0
(-450 2125);
DISPLAY 0.617021 (-450 2125);
PAINT SKYBLUE (-450 2125);
FORCEPROP 1 LAST LOCATION R3E1
J 0
(-550 2300);
DISPLAY 0.617021 (-550 2300);
PAINT AQUA (-550 2300);
FORCEPROP 1 LASTPIN (-400 2250) $PN 2
J 0
(-438 2262);
DISPLAY 0.617021 (-438 2262);
PAINT WHITE (-438 2262);
FORCEPROP 1 LAST PACK_TYPE 0402
J 0
(-450 2175);
DISPLAY 0.617021 (-450 2175);
PAINT SKYBLUE (-450 2175);
FORCEPROP 1 LAST WATTAGE 1/16W
J 2
(-475 2125);
DISPLAY 0.617021 (-475 2125);
PAINT SKYBLUE (-475 2125);
FORCEPROP 1 LAST PART_NUMBER G21796-017
J 0
(-650 2075);
DISPLAY 0.617021 (-650 2075);
PAINT BLUE (-650 2075);
FORCEPROP 2 LAST CDS_LIB mstr_discrete
J 0
(-500 2250);
PAINT ORANGE (-500 2250);
DISPLAY INVISIBLE (-500 2250);
FORCEPROP 0 LAST BOM_COST PROC_VRD_VCCIO_CPU1
J 0
(-550 2350);
DISPLAY 0.723404 (-550 2350);
PAINT ORANGE (-550 2350);
DISPLAY INVISIBLE (-550 2350);
FORCEPROP 2 LAST SEC_TYPE 0402
J 0
(-550 2446);
DISPLAY 1.021277 (-550 2446);
PAINT ORANGE (-550 2446);
DISPLAY INVISIBLE (-550 2446);
FORCEPROP 2 LAST SEC 1
J 0
(-550 2446);
DISPLAY 0.680851 (-550 2446);
PAINT MONO (-550 2446);
DISPLAY INVISIBLE (-550 2446);
FORCEPROP 1 LAST PATH I105
J 0
(-550 2400);
DISPLAY 0.978723 (-550 2400);
PAINT WHITE (-550 2400);
DISPLAY INVISIBLE (-550 2400);
FORCEPROP 2 LAST ROOM PVCCIO_CPU1
J 0
(-550 2400);
DISPLAY 0.723404 (-550 2400);
PAINT ORANGE (-550 2400);
DISPLAY INVISIBLE (-550 2400);
FORCEPROP 2 LAST CDS_LOCATION R3E1
J 0
(-550 2300);
DISPLAY 0.617021 (-550 2300);
PAINT AQUA (-550 2300);
DISPLAY INVISIBLE (-550 2300);
FORCEADD OFFPAGE..2
(-50 1750);
FORCEPROP 2 LAST $XR0 213 
J 0
(139 1750);
DISPLAY 0.638298 (139 1750);
PAINT MONO (139 1750);
FORCEPROP 2 LAST PATH I106
J 0
(150 1800);
DISPLAY 1.021277 (150 1800);
PAINT ORANGE (150 1800);
DISPLAY INVISIBLE (150 1800);
FORCEPROP 1 LAST OFFPAGE TRUE
J 0
(275 1625);
DISPLAY 0.872340 (275 1625);
PAINT GREEN (275 1625);
DISPLAY INVISIBLE (275 1625);
FORCEPROP 2 LAST ROOM PVCCIO_CPU0
J 0
(225 1775);
DISPLAY 0.617021 (225 1775);
PAINT ORANGE (225 1775);
DISPLAY INVISIBLE (225 1775);
FORCEPROP 1 LAST COMMENT_BODY TRUE
J 0
(-95 1655);
DISPLAY 0.872340 (-95 1655);
PAINT GREEN (-95 1655);
DISPLAY INVISIBLE (-95 1655);
FORCEPROP 2 LAST CDS_LIB mstr_standard
J 0
(-50 1750);
PAINT ORANGE (-50 1750);
DISPLAY INVISIBLE (-50 1750);
FORCEADD PVCCIO_CPU1..1
(-250 2525);
FORCEPROP 3 LASTPIN (-250 2475) SIG_NAME PVCCIO_CPU1\g
J 0
(-240 2485);
DISPLAY 0.659574 (-240 2485);
PAINT MONO (-240 2485);
DISPLAY INVISIBLE (-240 2485);
FORCEPROP 1 LAST HDL_POWER PVCCIO_CPU1
J 1
(-250 2575);
DISPLAY 0.872340 (-250 2575);
PAINT GREEN (-250 2575);
DISPLAY INVISIBLE (-250 2575);
FORCEPROP 2 LAST CDS_LIB mstr_symbols
J 0
(-250 2525);
PAINT ORANGE (-250 2525);
DISPLAY INVISIBLE (-250 2525);
FORCEPROP 1 LAST PATH I107
J 0
(-200 2550);
DISPLAY 0.872340 (-200 2550);
PAINT AQUA (-200 2550);
DISPLAY INVISIBLE (-200 2550);
FORCEPROP 1 LAST BODY_TYPE PLUMBING
J 0
(-295 2482);
DISPLAY 0.340426 (-295 2482);
PAINT GREEN (-295 2482);
DISPLAY INVISIBLE (-295 2482);
FORCEPROP 1 LAST VOLTAGE 1.1V
J 0
(-295 2482);
DISPLAY 0.340426 (-295 2482);
PAINT SKYBLUE (-295 2482);
DISPLAY INVISIBLE (-295 2482);
FORCEADD CAP_A..1
(3575 3000);
FORCEPROP 1 LAST LOCATION C3E1
J 0
(3396 3097);
DISPLAY 0.617021 (3396 3097);
PAINT AQUA (3396 3097);
FORCEPROP 1 LAST MATERIAL X6S
J 0
(3625 2900);
DISPLAY 0.617021 (3625 2900);
PAINT SKYBLUE (3625 2900);
FORCEPROP 1 LAST VALUE 22.0UF
J 0
(3625 3050);
DISPLAY 0.617021 (3625 3050);
PAINT SKYBLUE (3625 3050);
FORCEPROP 1 LAST PART_NUMBER E15431-004
J 0
(3625 2850);
DISPLAY 0.617021 (3625 2850);
PAINT BLUE (3625 2850);
FORCEPROP 1 LAST TOLERANCE 20%
J 0
(3625 2950);
DISPLAY 0.617021 (3625 2950);
PAINT SKYBLUE (3625 2950);
FORCEPROP 1 LAST PACK_TYPE 0603V
J 0
(3625 2800);
DISPLAY 0.617021 (3625 2800);
PAINT SKYBLUE (3625 2800);
FORCEPROP 1 LAST VOLTAGE 4V
J 0
(3625 3000);
DISPLAY 0.617021 (3625 3000);
PAINT SKYBLUE (3625 3000);
FORCEPROP 1 LASTPIN (3575 3100) $PN 1
J 0
(3585 3080);
DISPLAY 0.787234 (3585 3080);
PAINT ORANGE (3585 3080);
DISPLAY INVISIBLE (3585 3080);
FORCEPROP 2 LAST ROOM PVCCIO_CPU1
J 0
(3625 3150);
DISPLAY 0.723404 (3625 3150);
PAINT ORANGE (3625 3150);
DISPLAY INVISIBLE (3625 3150);
FORCEPROP 1 LAST PATH I108
J 0
(3625 3150);
DISPLAY 0.978723 (3625 3150);
PAINT WHITE (3625 3150);
DISPLAY INVISIBLE (3625 3150);
FORCEPROP 2 LAST $SEC 1
J 0
(3625 3200);
PAINT MONO (3625 3200);
DISPLAY INVISIBLE (3625 3200);
FORCEPROP 2 LAST CDS_SEC 1
J 0
(3625 3200);
PAINT MONO (3625 3200);
DISPLAY INVISIBLE (3625 3200);
FORCEPROP 2 LAST BOM_COST PROC_VRD_PVCCIO_CPU1
J 0
(3625 3150);
DISPLAY 0.723404 (3625 3150);
PAINT ORANGE (3625 3150);
DISPLAY INVISIBLE (3625 3150);
FORCEPROP 2 LAST REUSE_ID 281
J 0
(3625 3200);
DISPLAY 0.723404 (3625 3200);
PAINT MONO (3625 3200);
DISPLAY INVISIBLE (3625 3200);
FORCEPROP 2 LAST CDS_LOCATION C3E1
J 0
(3396 3097);
DISPLAY 0.617021 (3396 3097);
PAINT AQUA (3396 3097);
DISPLAY INVISIBLE (3396 3097);
FORCEPROP 1 LASTPIN (3575 2900) $PN 2
J 0
(3585 2880);
DISPLAY 0.787234 (3585 2880);
PAINT ORANGE (3585 2880);
DISPLAY INVISIBLE (3585 2880);
FORCEPROP 2 LAST CDS_LIB dev_discrete
J 0
(3575 3000);
PAINT ORANGE (3575 3000);
DISPLAY INVISIBLE (3575 3000);
FORCEADD RES..2
(3875 2975);
FORCEPROP 1 LAST PART_NUMBER G21796-208
J 0
(3915 2850);
DISPLAY 0.617021 (3915 2850);
PAINT BLUE (3915 2850);
FORCEPROP 1 LAST LOCATION R7R1
J 0
(3920 3100);
DISPLAY 0.617021 (3920 3100);
PAINT AQUA (3920 3100);
FORCEPROP 1 LAST VALUE 51.1
J 0
(3920 3050);
DISPLAY 0.617021 (3920 3050);
PAINT SKYBLUE (3920 3050);
FORCEPROP 1 LAST WATTAGE 1/16W
J 0
(3915 2950);
DISPLAY 0.617021 (3915 2950);
PAINT SKYBLUE (3915 2950);
FORCEPROP 1 LAST MATERIAL CHIP
J 0
(3915 2900);
DISPLAY 0.617021 (3915 2900);
PAINT SKYBLUE (3915 2900);
FORCEPROP 1 LAST TOLERANCE 1.0%
J 0
(3920 3000);
DISPLAY 0.617021 (3920 3000);
PAINT SKYBLUE (3920 3000);
FORCEPROP 1 LAST PACK_TYPE 0402
J 0
(3915 2800);
DISPLAY 0.617021 (3915 2800);
PAINT SKYBLUE (3915 2800);
FORCEPROP 2 LAST CDS_SEC 1
J 0
(3925 3200);
PAINT MONO (3925 3200);
DISPLAY INVISIBLE (3925 3200);
FORCEPROP 2 LAST $SEC 1
J 0
(3925 3200);
PAINT MONO (3925 3200);
DISPLAY INVISIBLE (3925 3200);
FORCEPROP 1 LAST PATH I109
J 0
(3925 3150);
DISPLAY 0.978723 (3925 3150);
PAINT WHITE (3925 3150);
DISPLAY INVISIBLE (3925 3150);
FORCEPROP 2 LAST CDS_LOCATION R7R1
J 0
(3920 3100);
DISPLAY 0.617021 (3920 3100);
PAINT AQUA (3920 3100);
DISPLAY INVISIBLE (3920 3100);
FORCEPROP 2 LAST CDS_LIB mstr_discrete
J 0
(3875 2975);
PAINT ORANGE (3875 2975);
DISPLAY INVISIBLE (3875 2975);
FORCEPROP 1 LASTPIN (3875 2875) $PN 2
J 0
(3880 2885);
DISPLAY 0.787234 (3880 2885);
PAINT ORANGE (3880 2885);
DISPLAY INVISIBLE (3880 2885);
FORCEPROP 1 LASTPIN (3875 3075) $PN 1
J 0
(3880 3037);
DISPLAY 0.787234 (3880 3037);
PAINT ORANGE (3880 3037);
DISPLAY INVISIBLE (3880 3037);
FORCEADD IR354XX..1
(850 3475);
FORCEPROP 1 LAST PART_NUMBER H73684-001
J 0
(500 2775);
DISPLAY 0.617021 (500 2775);
PAINT BLUE (500 2775);
FORCEPROP 2 LASTPIN (350 3375) $PN 34
J 2
(340 3385);
DISPLAY 0.617021 (340 3385);
PAINT ORANGE (340 3385);
FORCEPROP 2 LASTPIN (1350 3525) $PN 36
J 0
(1360 3535);
DISPLAY 0.617021 (1360 3535);
PAINT ORANGE (1360 3535);
FORCEPROP 1 LAST LOCATION EU4E2
J 0
(400 4275);
DISPLAY 0.617021 (400 4275);
PAINT AQUA (400 4275);
FORCEPROP 1 LAST VALUE IR35412
J 1
(850 4100);
DISPLAY 0.617021 (850 4100);
PAINT SKYBLUE (850 4100);
FORCEPROP 1 LAST MATERIAL IC
J 0
(400 4225);
DISPLAY 0.617021 (400 4225);
PAINT SKYBLUE (400 4225);
FORCEPROP 2 LAST NO_XNET_CONNECTION 1
J 0
(400 4325);
PAINT MONO (400 4325);
FORCEPROP 2 LASTPIN (1350 4025) $PN 38
J 0
(1360 4035);
DISPLAY 0.617021 (1360 4035);
PAINT ORANGE (1360 4035);
FORCEPROP 2 LASTPIN (1350 3775) $PN 31
J 0
(1360 3785);
DISPLAY 0.617021 (1360 3785);
PAINT ORANGE (1360 3785);
FORCEPROP 2 LASTPIN (1350 3825) $PN 37
J 0
(1360 3835);
DISPLAY 0.617021 (1360 3835);
PAINT ORANGE (1360 3835);
FORCEPROP 2 LASTPIN (1350 3175) $PN 10
J 0
(1360 3185);
DISPLAY 0.617021 (1360 3185);
PAINT ORANGE (1360 3185);
FORCEPROP 2 LASTPIN (1350 3075) $PN 2
J 0
(1360 3085);
DISPLAY 0.617021 (1360 3085);
PAINT ORANGE (1360 3085);
FORCEPROP 2 LASTPIN (1350 3025) $PN 40
J 0
(1360 3035);
DISPLAY 0.617021 (1360 3035);
PAINT ORANGE (1360 3035);
FORCEPROP 2 LASTPIN (1350 2925) $PN 5
J 0
(1360 2935);
DISPLAY 0.617021 (1360 2935);
PAINT ORANGE (1360 2935);
FORCEPROP 2 LASTPIN (1350 2975) $PN 7
J 0
(1360 2985);
DISPLAY 0.617021 (1360 2985);
PAINT ORANGE (1360 2985);
FORCEPROP 2 LASTPIN (350 3925) $PN 25
J 2
(340 3935);
DISPLAY 0.617021 (340 3935);
PAINT ORANGE (340 3935);
FORCEPROP 2 LASTPIN (350 3975) $PN 30
J 2
(340 3985);
DISPLAY 0.617021 (340 3985);
PAINT ORANGE (340 3985);
FORCEPROP 2 LASTPIN (350 4025) $PN 3
J 2
(340 4035);
DISPLAY 0.617021 (340 4035);
PAINT ORANGE (340 4035);
FORCEPROP 2 LASTPIN (350 3825) $PN 4
J 2
(340 3835);
DISPLAY 0.617021 (340 3835);
PAINT ORANGE (340 3835);
FORCEPROP 2 LASTPIN (350 3725) $PN 35
J 2
(340 3735);
DISPLAY 0.617021 (340 3735);
PAINT ORANGE (340 3735);
FORCEPROP 2 LASTPIN (350 3625) $PN 1
J 2
(340 3635);
DISPLAY 0.617021 (340 3635);
PAINT ORANGE (340 3635);
FORCEPROP 2 LASTPIN (350 3525) $PN 41
J 2
(340 3535);
DISPLAY 0.617021 (340 3535);
PAINT ORANGE (340 3535);
FORCEPROP 2 LASTPIN (350 3475) $PN 6
J 2
(340 3485);
DISPLAY 0.617021 (340 3485);
PAINT ORANGE (340 3485);
FORCEPROP 2 LASTPIN (350 3175) $PN 33
J 2
(340 3185);
DISPLAY 0.617021 (340 3185);
PAINT ORANGE (340 3185);
FORCEPROP 2 LASTPIN (350 3125) $PN 32
J 2
(340 3135);
DISPLAY 0.617021 (340 3135);
PAINT ORANGE (340 3135);
FORCEPROP 2 LASTPIN (350 3275) $PN 39
J 2
(340 3285);
DISPLAY 0.617021 (340 3285);
PAINT ORANGE (340 3285);
FORCEPROP 1 LAST PACK_TYPE SM
J 0
(400 4325);
PAINT SKYBLUE (400 4325);
DISPLAY INVISIBLE (400 4325);
FORCEPROP 1 LAST PATH I126
J 0
(850 4225);
PAINT GREEN (850 4225);
DISPLAY INVISIBLE (850 4225);
FORCEPROP 2 LAST CDS_LOCATION EU4E2
J 0
(400 4275);
PAINT GREEN (400 4275);
DISPLAY INVISIBLE (400 4275);
FORCEPROP 2 LAST SEC 1
J 0
(400 4325);
DISPLAY 0.680851 (400 4325);
PAINT MONO (400 4325);
DISPLAY INVISIBLE (400 4325);
FORCEPROP 2 LAST SEC_TYPE SM
J 0
(400 4325);
DISPLAY 1.021277 (400 4325);
PAINT ORANGE (400 4325);
DISPLAY INVISIBLE (400 4325);
FORCEPROP 2 LAST CDS_LIB mstr_discrete
J 0
(850 3475);
PAINT ORANGE (850 3475);
DISPLAY INVISIBLE (850 3475);
FORCEADD RES..2
(3175 3625);
FORCEPROP 1 LAST LOCATION R4E21
J 0
(3220 3750);
DISPLAY 0.617021 (3220 3750);
PAINT AQUA (3220 3750);
FORCEPROP 1 LAST VALUE 68.1K
J 0
(3220 3700);
DISPLAY 0.617021 (3220 3700);
PAINT SKYBLUE (3220 3700);
FORCEPROP 1 LAST WATTAGE 1/16W
J 0
(3215 3600);
DISPLAY 0.617021 (3215 3600);
PAINT SKYBLUE (3215 3600);
FORCEPROP 1 LAST TOLERANCE 1%
J 0
(3220 3650);
DISPLAY 0.617021 (3220 3650);
PAINT SKYBLUE (3220 3650);
FORCEPROP 1 LAST MATERIAL EMPTY
J 0
(3215 3550);
DISPLAY 0.617021 (3215 3550);
PAINT RED (3215 3550);
FORCEPROP 1 LAST PART_NUMBER G21796-187
J 0
(3215 3500);
DISPLAY 0.617021 (3215 3500);
PAINT BLUE (3215 3500);
FORCEPROP 1 LAST PACK_TYPE 0402
J 0
(3215 3450);
DISPLAY 0.617021 (3215 3450);
PAINT SKYBLUE (3215 3450);
FORCEPROP 2 LAST $SEC 1
J 0
(3225 3850);
PAINT MONO (3225 3850);
DISPLAY INVISIBLE (3225 3850);
FORCEPROP 2 LAST CDS_SEC 1
J 0
(3225 3850);
PAINT MONO (3225 3850);
DISPLAY INVISIBLE (3225 3850);
FORCEPROP 1 LAST PATH I127
J 0
(3225 3800);
DISPLAY 0.978723 (3225 3800);
PAINT WHITE (3225 3800);
DISPLAY INVISIBLE (3225 3800);
FORCEPROP 1 LASTPIN (3175 3725) $PN 1
J 0
(3180 3687);
DISPLAY 0.787234 (3180 3687);
PAINT ORANGE (3180 3687);
DISPLAY INVISIBLE (3180 3687);
FORCEPROP 2 LAST CDS_LIB mstr_discrete
J 0
(3175 3625);
PAINT ORANGE (3175 3625);
DISPLAY INVISIBLE (3175 3625);
FORCEPROP 1 LASTPIN (3175 3525) $PN 2
J 0
(3180 3535);
DISPLAY 0.787234 (3180 3535);
PAINT ORANGE (3180 3535);
DISPLAY INVISIBLE (3180 3535);
FORCEADD GND..1
(3175 3375);
FORCEPROP 3 LASTPIN (3175 3425) SIG_NAME GND\g
J 0
(3185 3435);
DISPLAY 0.659574 (3185 3435);
PAINT MONO (3185 3435);
DISPLAY INVISIBLE (3185 3435);
FORCEPROP 1 LAST HDL_POWER GND
J 0
(3175 3525);
DISPLAY 1.723404 (3175 3525);
PAINT GREEN (3175 3525);
DISPLAY INVISIBLE (3175 3525);
FORCEPROP 1 LAST PATH I128
J 0
(3250 3375);
DISPLAY 0.872340 (3250 3375);
PAINT AQUA (3250 3375);
DISPLAY INVISIBLE (3250 3375);
FORCEPROP 1 LAST VOLTAGE 0
J 0
(3175 3375);
PAINT SKYBLUE (3175 3375);
DISPLAY INVISIBLE (3175 3375);
FORCEPROP 1 LAST BODY_TYPE PLUMBING
J 0
(3130 3332);
DISPLAY 0.340426 (3130 3332);
PAINT GREEN (3130 3332);
DISPLAY INVISIBLE (3130 3332);
FORCEPROP 2 LAST CDS_LIB mstr_symbols
J 0
(3175 3375);
PAINT ORANGE (3175 3375);
DISPLAY INVISIBLE (3175 3375);
FORCEPROP 1 LAST SIZE 1B
J 0
(3250 3325);
DISPLAY 1.723404 (3250 3325);
PAINT GREEN (3250 3325);
DISPLAY INVISIBLE (3250 3325);
FORCEPROP 2 LAST ROOM PVSA_CPU1_PWR_VR
J 0
(2625 3450);
DISPLAY 1.936170 (2625 3450);
PAINT ORANGE (2625 3450);
DISPLAY INVISIBLE (2625 3450);
FORCEPROP 2 LAST BOM_COST PROC_VRD_VCCIN_CPU0
J 0
(2800 3450);
DISPLAY 1.446809 (2800 3450);
PAINT MONO (2800 3450);
DISPLAY INVISIBLE (2800 3450);
FORCEADD SHUNT..1
(-1125 1750);
FORCEPROP 1 LASTPIN (-975 1750) $PN 2
J 0
(-1015 1760);
DISPLAY 0.617021 (-1015 1760);
PAINT ORANGE (-1015 1760);
FORCEPROP 1 LAST LOCATION SH3D2
J 0
(-1200 1800);
DISPLAY 0.617021 (-1200 1800);
PAINT AQUA (-1200 1800);
FORCEPROP 1 LAST PART_NUMBER N_A
J 0
(-1200 1660);
DISPLAY 0.617021 (-1200 1660);
PAINT BLUE (-1200 1660);
FORCEPROP 1 LASTPIN (-1275 1750) $PN 1
J 2
(-1225 1760);
DISPLAY 0.617021 (-1225 1760);
PAINT ORANGE (-1225 1760);
FORCEPROP 2 LAST SEC_TYPE SH0201
J 0
(-1175 1900);
DISPLAY 1.021277 (-1175 1900);
PAINT ORANGE (-1175 1900);
DISPLAY INVISIBLE (-1175 1900);
FORCEPROP 0 LAST SEC 1
J 0
(-1200 1850);
DISPLAY 0.680851 (-1200 1850);
PAINT MONO (-1200 1850);
DISPLAY INVISIBLE (-1200 1850);
FORCEPROP 1 LAST PATH I129
J 0
(-1175 1850);
DISPLAY 0.978723 (-1175 1850);
PAINT ORANGE (-1175 1850);
DISPLAY INVISIBLE (-1175 1850);
FORCEPROP 2 LAST CDS_LIB mstr_misc
J 0
(-1125 1750);
PAINT ORANGE (-1125 1750);
DISPLAY INVISIBLE (-1125 1750);
FORCEPROP 1 LAST MATERIAL EMPTY
J 0
(-1200 1615);
DISPLAY 0.978723 (-1200 1615);
PAINT RED (-1200 1615);
DISPLAY INVISIBLE (-1200 1615);
FORCEPROP 1 LAST PACK_TYPE SH0201
J 0
(-1185 1565);
DISPLAY 0.978723 (-1185 1565);
PAINT SKYBLUE (-1185 1565);
DISPLAY INVISIBLE (-1185 1565);
FORCEPROP 1 LAST PIN_SHORT A:B
J 0
(-1200 1500);
DISPLAY 1.021277 (-1200 1500);
PAINT ORANGE (-1200 1500);
DISPLAY INVISIBLE (-1200 1500);
FORCEADD SHUNT..1
(-1125 1300);
FORCEPROP 1 LASTPIN (-975 1300) $PN 2
J 0
(-1015 1310);
DISPLAY 0.617021 (-1015 1310);
PAINT ORANGE (-1015 1310);
FORCEPROP 1 LAST LOCATION SH3D1
J 0
(-1200 1350);
DISPLAY 0.617021 (-1200 1350);
PAINT AQUA (-1200 1350);
FORCEPROP 1 LASTPIN (-1275 1300) $PN 1
J 2
(-1225 1310);
DISPLAY 0.617021 (-1225 1310);
PAINT ORANGE (-1225 1310);
FORCEPROP 1 LAST PART_NUMBER N_A
J 0
(-1200 1210);
DISPLAY 0.617021 (-1200 1210);
PAINT BLUE (-1200 1210);
FORCEPROP 2 LAST CDS_LIB mstr_misc
J 0
(-1125 1300);
PAINT ORANGE (-1125 1300);
DISPLAY INVISIBLE (-1125 1300);
FORCEPROP 2 LAST SEC_TYPE SH0201
J 0
(-1175 1450);
DISPLAY 1.021277 (-1175 1450);
PAINT ORANGE (-1175 1450);
DISPLAY INVISIBLE (-1175 1450);
FORCEPROP 0 LAST SEC 1
J 0
(-1200 1400);
DISPLAY 0.680851 (-1200 1400);
PAINT MONO (-1200 1400);
DISPLAY INVISIBLE (-1200 1400);
FORCEPROP 1 LAST PATH I130
J 0
(-1175 1400);
DISPLAY 0.978723 (-1175 1400);
PAINT ORANGE (-1175 1400);
DISPLAY INVISIBLE (-1175 1400);
FORCEPROP 1 LAST MATERIAL EMPTY
J 0
(-1200 1165);
DISPLAY 0.978723 (-1200 1165);
PAINT RED (-1200 1165);
DISPLAY INVISIBLE (-1200 1165);
FORCEPROP 1 LAST PACK_TYPE SH0201
J 0
(-1185 1115);
DISPLAY 0.978723 (-1185 1115);
PAINT SKYBLUE (-1185 1115);
DISPLAY INVISIBLE (-1185 1115);
FORCEPROP 1 LAST PIN_SHORT A:B
J 0
(-1200 1050);
DISPLAY 1.021277 (-1200 1050);
PAINT ORANGE (-1200 1050);
DISPLAY INVISIBLE (-1200 1050);
FORCEADD SC2K2P50V3KX-GP..1
(2150 3025);
FORCEPROP 1 LAST LOCATION CT62
J 0
(2175 3055);
DISPLAY 0.617021 (2175 3055);
PAINT GREEN (2175 3055);
FORCEPROP 1 LAST VALUE SC2K2P50V3KX-GP
J 0
(2175 2975);
DISPLAY 0.617021 (2175 2975);
PAINT GREEN (2175 2975);
FORCEPROP 0 LAST STATUS NOPOP
J 0
(1875 3000);
DISPLAY 1.021277 (1875 3000);
PAINT ORANGE (1875 3000);
FORCEPROP 1 LAST PACK_TYPE SMD-BCG6
J 0
(2150 3025);
DISPLAY 0.617021 (2150 3025);
PAINT GREEN (2150 3025);
DISPLAY INVISIBLE (2150 3025);
FORCEPROP 1 LAST PART_NUMBER 78.22224.2BL
J 0
(2150 3025);
DISPLAY 0.617021 (2150 3025);
PAINT GREEN (2150 3025);
DISPLAY INVISIBLE (2150 3025);
FORCEPROP 1 LAST PATH I131
J 0
(2150 3025);
DISPLAY 0.617021 (2150 3025);
PAINT GREEN (2150 3025);
DISPLAY INVISIBLE (2150 3025);
FORCEPROP 2 LAST CDS_LIB w_hdl
J 0
(2150 3025);
PAINT MONO (2150 3025);
DISPLAY INVISIBLE (2150 3025);
FORCEPROP 1 LAST CDS_LMAN_SYM_OUTLINE -50,25,50,-25
J 0
(2150 3025);
DISPLAY 0.468085 (2150 3025);
PAINT GREEN (2150 3025);
DISPLAY INVISIBLE (2150 3025);
FORCEADD 3D01R5F-GP..1
R 4
(2150 2725);
FORCEPROP 1 LAST VALUE 3D01R5F-GP
J 0
(1900 2775);
DISPLAY 0.617021 (1900 2775);
PAINT GREEN (1900 2775);
FORCEPROP 0 LAST STATUS NOPOP
J 0
(1875 2800);
DISPLAY 1.021277 (1875 2800);
PAINT ORANGE (1875 2800);
FORCEPROP 1 LAST LOCATION RT42
J 0
(2025 2720);
DISPLAY 0.617021 (2025 2720);
PAINT GREEN (2025 2720);
FORCEPROP 2 LASTPIN (2150 2850) SIG_NAME UN$214$3D01R5F-GP$I132$2
J 0
(2160 2860);
DISPLAY 0.659574 (2160 2860);
PAINT MONO (2160 2860);
DISPLAY INVISIBLE (2160 2860);
FORCEPROP 1 LAST PACK_TYPE SMD-RG5
R 2
J 0
(2150 2725);
DISPLAY 0.617021 (2150 2725);
PAINT GREEN (2150 2725);
DISPLAY INVISIBLE (2150 2725);
FORCEPROP 1 LAST PART_NUMBER 64.3R015.16L
R 2
J 0
(2150 2725);
DISPLAY 0.617021 (2150 2725);
PAINT GREEN (2150 2725);
DISPLAY INVISIBLE (2150 2725);
FORCEPROP 2 LAST CDS_LIB w_hdl
J 0
(2150 2725);
PAINT MONO (2150 2725);
DISPLAY INVISIBLE (2150 2725);
FORCEPROP 1 LAST PATH I132
R 2
J 0
(2150 2725);
DISPLAY 0.617021 (2150 2725);
PAINT GREEN (2150 2725);
DISPLAY INVISIBLE (2150 2725);
FORCEPROP 1 LAST CDS_LMAN_SYM_OUTLINE -50,75,50,-75
R 2
J 0
(2150 2725);
DISPLAY 0.468085 (2150 2725);
PAINT GREEN (2150 2725);
DISPLAY INVISIBLE (2150 2725);
FORCEADD GND..1
(2150 2525);
FORCEPROP 3 LASTPIN (2150 2575) SIG_NAME GND\g
J 0
(2160 2585);
DISPLAY 0.659574 (2160 2585);
PAINT MONO (2160 2585);
DISPLAY INVISIBLE (2160 2585);
FORCEPROP 2 LAST CDS_LIB mstr_symbols
J 0
(2150 2525);
PAINT MONO (2150 2525);
DISPLAY INVISIBLE (2150 2525);
FORCEPROP 2 LAST ROOM PVCCIN_CPU0_PWR_VR
J 0
(1600 2600);
DISPLAY 1.936170 (1600 2600);
PAINT ORANGE (1600 2600);
DISPLAY INVISIBLE (1600 2600);
FORCEPROP 2 LAST BOM_COST PROC_VRD_VCCIN_CPU0
J 0
(1775 2600);
DISPLAY 1.446809 (1775 2600);
PAINT MONO (1775 2600);
DISPLAY INVISIBLE (1775 2600);
FORCEPROP 1 LAST BODY_TYPE PLUMBING
J 0
(2105 2482);
DISPLAY 0.340426 (2105 2482);
PAINT GREEN (2105 2482);
DISPLAY INVISIBLE (2105 2482);
FORCEPROP 1 LAST VOLTAGE 0
J 0
(2150 2525);
PAINT SKYBLUE (2150 2525);
DISPLAY INVISIBLE (2150 2525);
FORCEPROP 1 LAST SIZE 1B
J 0
(2225 2475);
DISPLAY 1.723404 (2225 2475);
PAINT GREEN (2225 2475);
DISPLAY INVISIBLE (2225 2475);
FORCEPROP 1 LAST HDL_POWER GND
J 0
(2150 2675);
DISPLAY 1.723404 (2150 2675);
PAINT GREEN (2150 2675);
DISPLAY INVISIBLE (2150 2675);
FORCEPROP 1 LAST PATH I133
J 0
(2225 2525);
DISPLAY 0.872340 (2225 2525);
PAINT AQUA (2225 2525);
DISPLAY INVISIBLE (2225 2525);
FORCEADD CAP..1
(2050 3500);
FORCEPROP 1 LAST VOLTAGE 50V
J 0
(2100 3500);
DISPLAY 0.617021 (2100 3500);
PAINT SKYBLUE (2100 3500);
FORCEPROP 1 LAST TOLERANCE 10%
J 0
(2100 3450);
DISPLAY 0.617021 (2100 3450);
PAINT SKYBLUE (2100 3450);
FORCEPROP 1 LAST MATERIAL X7R
J 0
(2100 3400);
DISPLAY 0.617021 (2100 3400);
PAINT SKYBLUE (2100 3400);
FORCEPROP 1 LAST PART_NUMBER A36096-046
J 0
(2100 3350);
DISPLAY 0.617021 (2100 3350);
PAINT BLUE (2100 3350);
FORCEPROP 1 LAST VALUE 1000PF
J 0
(2100 3550);
DISPLAY 0.617021 (2100 3550);
PAINT SKYBLUE (2100 3550);
FORCEPROP 1 LAST PACK_TYPE 0402LF
J 0
(2100 3300);
DISPLAY 0.617021 (2100 3300);
PAINT SKYBLUE (2100 3300);
FORCEPROP 1 LAST LOCATION CT61
J 0
(1900 3500);
DISPLAY 0.617021 (1900 3500);
PAINT AQUA (1900 3500);
FORCEPROP 0 LAST STATUS NOPOP
J 0
(1825 3550);
DISPLAY 1.021277 (1825 3550);
PAINT ORANGE (1825 3550);
FORCEPROP 2 LAST CDS_LIB mstr_discrete
J 0
(2050 3500);
PAINT MONO (2050 3500);
DISPLAY INVISIBLE (2050 3500);
FORCEPROP 1 LAST PATH I134
J 0
(2100 3650);
DISPLAY 0.978723 (2100 3650);
PAINT WHITE (2100 3650);
DISPLAY INVISIBLE (2100 3650);
FORCEPROP 0 LAST ROOM VDDQ_KLM_PWR_VR
J 0
(2100 3700);
DISPLAY 1.021277 (2100 3700);
PAINT ORANGE (2100 3700);
DISPLAY INVISIBLE (2100 3700);
FORCEPROP 1 LASTPIN (2050 3400) $PN 2
J 0
(2060 3380);
DISPLAY 0.787234 (2060 3380);
PAINT ORANGE (2060 3380);
DISPLAY INVISIBLE (2060 3380);
FORCEPROP 1 LASTPIN (2050 3600) $PN 1
J 0
(2060 3580);
DISPLAY 0.787234 (2060 3580);
PAINT ORANGE (2060 3580);
DISPLAY INVISIBLE (2060 3580);
FORCEADD GND..1
(2050 3300);
FORCEPROP 3 LASTPIN (2050 3350) SIG_NAME GND\g
J 0
(2060 3360);
DISPLAY 0.659574 (2060 3360);
PAINT MONO (2060 3360);
DISPLAY INVISIBLE (2060 3360);
FORCEPROP 2 LAST CDS_LIB mstr_symbols
J 0
(2050 3300);
PAINT MONO (2050 3300);
DISPLAY INVISIBLE (2050 3300);
FORCEPROP 1 LAST PATH I135
J 0
(2125 3300);
DISPLAY 0.872340 (2125 3300);
PAINT AQUA (2125 3300);
DISPLAY INVISIBLE (2125 3300);
FORCEPROP 2 LAST ROOM VDDQ_KLM_PWR_VR
J 0
(1475 3375);
DISPLAY 1.361702 (1475 3375);
PAINT ORANGE (1475 3375);
DISPLAY INVISIBLE (1475 3375);
FORCEPROP 1 LAST VOLTAGE 0
J 0
(2050 3300);
PAINT SKYBLUE (2050 3300);
DISPLAY INVISIBLE (2050 3300);
FORCEPROP 1 LAST BODY_TYPE PLUMBING
J 0
(2005 3257);
DISPLAY 0.340426 (2005 3257);
PAINT GREEN (2005 3257);
DISPLAY INVISIBLE (2005 3257);
FORCEPROP 1 LAST SIZE 1B
J 0
(2125 3250);
DISPLAY 1.170213 (2125 3250);
PAINT AQUA (2125 3250);
DISPLAY INVISIBLE (2125 3250);
FORCEPROP 1 LAST HDL_POWER GND
J 0
(2050 3450);
DISPLAY 1.170213 (2050 3450);
PAINT GREEN (2050 3450);
DISPLAY INVISIBLE (2050 3450);
FORCEADD GND..1
(50 2725);
FORCEPROP 3 LASTPIN (50 2775) SIG_NAME GND\g
J 0
(60 2785);
DISPLAY 0.659574 (60 2785);
PAINT MONO (60 2785);
DISPLAY INVISIBLE (60 2785);
FORCEPROP 1 LAST HDL_POWER GND
J 0
(50 2875);
DISPLAY 1.723404 (50 2875);
PAINT GREEN (50 2875);
DISPLAY INVISIBLE (50 2875);
FORCEPROP 1 LAST VOLTAGE 0
J 0
(50 2725);
PAINT SKYBLUE (50 2725);
DISPLAY INVISIBLE (50 2725);
FORCEPROP 1 LAST SIZE 1B
J 0
(125 2675);
DISPLAY 1.723404 (125 2675);
PAINT GREEN (125 2675);
DISPLAY INVISIBLE (125 2675);
FORCEPROP 2 LAST BOM_COST PROC_VRD_VCCIN_CPU0
J 0
(-325 2800);
DISPLAY 1.446809 (-325 2800);
PAINT MONO (-325 2800);
DISPLAY INVISIBLE (-325 2800);
FORCEPROP 2 LAST ROOM PVCCIN_CPU0_PWR_VR
J 0
(-500 2800);
DISPLAY 1.936170 (-500 2800);
PAINT ORANGE (-500 2800);
DISPLAY INVISIBLE (-500 2800);
FORCEPROP 1 LAST BODY_TYPE PLUMBING
J 0
(5 2682);
DISPLAY 0.340426 (5 2682);
PAINT GREEN (5 2682);
DISPLAY INVISIBLE (5 2682);
FORCEPROP 1 LAST PATH I136
J 0
(125 2725);
DISPLAY 0.872340 (125 2725);
PAINT AQUA (125 2725);
DISPLAY INVISIBLE (125 2725);
FORCEPROP 2 LAST CDS_LIB mstr_symbols
J 0
(50 2725);
PAINT MONO (50 2725);
DISPLAY INVISIBLE (50 2725);
FORCEADD CAP_A..1
(50 2975);
FORCEPROP 0 LAST STATUS NOPOP
J 0
(-200 3025);
DISPLAY 1.021277 (-200 3025);
PAINT ORANGE (-200 3025);
FORCEPROP 1 LAST LOCATION CT63
J 0
(-100 2975);
DISPLAY 0.617021 (-100 2975);
PAINT AQUA (-100 2975);
FORCEPROP 1 LAST VALUE 0.1UF
J 0
(100 3025);
DISPLAY 0.617021 (100 3025);
PAINT SKYBLUE (100 3025);
FORCEPROP 1 LAST PACK_TYPE 0402V
J 0
(100 2775);
DISPLAY 0.617021 (100 2775);
PAINT SKYBLUE (100 2775);
FORCEPROP 1 LAST PART_NUMBER A36096-030
J 0
(100 2825);
DISPLAY 0.617021 (100 2825);
PAINT BLUE (100 2825);
FORCEPROP 1 LAST MATERIAL X7R
J 0
(100 2875);
DISPLAY 0.617021 (100 2875);
PAINT SKYBLUE (100 2875);
FORCEPROP 1 LAST TOLERANCE 10%
J 0
(100 2925);
DISPLAY 0.617021 (100 2925);
PAINT SKYBLUE (100 2925);
FORCEPROP 1 LAST VOLTAGE 16V
J 0
(100 2975);
DISPLAY 0.617021 (100 2975);
PAINT SKYBLUE (100 2975);
FORCEPROP 2 LAST ROOM PVCCIN_CPU0_PWR_VR
J 0
(100 3125);
DISPLAY 1.361702 (100 3125);
PAINT ORANGE (100 3125);
DISPLAY INVISIBLE (100 3125);
FORCEPROP 1 LAST PATH I137
J 0
(100 3125);
DISPLAY 0.978723 (100 3125);
PAINT WHITE (100 3125);
DISPLAY INVISIBLE (100 3125);
FORCEPROP 2 LAST CDS_LIB dev_discrete
J 0
(50 2975);
PAINT MONO (50 2975);
DISPLAY INVISIBLE (50 2975);
FORCEPROP 1 LASTPIN (50 3075) $PN 1
J 0
(60 3055);
DISPLAY 0.787234 (60 3055);
PAINT ORANGE (60 3055);
DISPLAY INVISIBLE (60 3055);
FORCEPROP 1 LASTPIN (50 2875) $PN 2
J 0
(60 2855);
DISPLAY 0.787234 (60 2855);
PAINT ORANGE (60 2855);
DISPLAY INVISIBLE (60 2855);
FORCEADD RES..1
(-950 3250);
FORCEPROP 1 LAST LOCATION RT41
J 0
(-1000 3275);
DISPLAY 0.617021 (-1000 3275);
PAINT AQUA (-1000 3275);
FORCEPROP 1 LAST WATTAGE 1/16W
J 2
(-975 3100);
DISPLAY 0.617021 (-975 3100);
PAINT SKYBLUE (-975 3100);
FORCEPROP 1 LAST PACK_TYPE 0402
J 0
(-850 3100);
DISPLAY 0.617021 (-850 3100);
PAINT SKYBLUE (-850 3100);
FORCEPROP 1 LAST VALUE 0.0
J 2
(-975 3150);
DISPLAY 0.617021 (-975 3150);
PAINT SKYBLUE (-975 3150);
FORCEPROP 1 LAST PART_NUMBER G21497-005
J 0
(-1050 3200);
DISPLAY 0.617021 (-1050 3200);
PAINT BLUE (-1050 3200);
FORCEPROP 1 LAST TOLERANCE 5%
J 0
(-950 3150);
DISPLAY 0.617021 (-950 3150);
PAINT SKYBLUE (-950 3150);
FORCEPROP 1 LAST MATERIAL CHIP
J 0
(-950 3100);
DISPLAY 0.617021 (-950 3100);
PAINT SKYBLUE (-950 3100);
FORCEPROP 2 LAST CDS_LIB mstr_discrete
J 0
(-950 3250);
PAINT MONO (-950 3250);
DISPLAY INVISIBLE (-950 3250);
FORCEPROP 1 LAST PATH I139
J 0
(-1000 3400);
DISPLAY 0.978723 (-1000 3400);
PAINT WHITE (-1000 3400);
DISPLAY INVISIBLE (-1000 3400);
FORCEPROP 2 LAST BOM_COST DEBUG
J 0
(-1000 3450);
DISPLAY 1.021277 (-1000 3450);
PAINT ORANGE (-1000 3450);
DISPLAY INVISIBLE (-1000 3450);
FORCEPROP 2 LAST ROOM BMC_DEBUG_HEADER
J 0
(-1000 3400);
DISPLAY 1.021277 (-1000 3400);
PAINT ORANGE (-1000 3400);
DISPLAY INVISIBLE (-1000 3400);
FORCEPROP 1 LASTPIN (-1050 3250) $PN 1
J 0
(-1038 3262);
DISPLAY 0.787234 (-1038 3262);
PAINT ORANGE (-1038 3262);
DISPLAY INVISIBLE (-1038 3262);
FORCEPROP 1 LASTPIN (-850 3250) $PN 2
J 0
(-888 3262);
DISPLAY 0.787234 (-888 3262);
PAINT ORANGE (-888 3262);
DISPLAY INVISIBLE (-888 3262);
FORCEADD CAPP..1
R 2
(3375 2200);
FORCEPROP 1 LASTPIN (3375 2300) $PN 1
J 2
(3365 2285);
DISPLAY 0.617021 (3365 2285);
PAINT WHITE (3365 2285);
FORCEPROP 1 LASTPIN (3375 2100) $PN 2
J 2
(3365 2085);
DISPLAY 0.617021 (3365 2085);
PAINT WHITE (3365 2085);
FORCEPROP 1 LAST LOCATION C4E7
J 2
(3325 2300);
DISPLAY 0.617021 (3325 2300);
PAINT AQUA (3325 2300);
FORCEPROP 1 LAST VALUE 470UF
J 2
(3325 2250);
DISPLAY 0.617021 (3325 2250);
PAINT SKYBLUE (3325 2250);
FORCEPROP 1 LAST TOLERANCE 20%
J 2
(3325 2200);
DISPLAY 0.617021 (3325 2200);
PAINT SKYBLUE (3325 2200);
FORCEPROP 1 LAST PACK_TYPE 3018
J 2
(3325 2050);
DISPLAY 0.617021 (3325 2050);
PAINT SKYBLUE (3325 2050);
FORCEPROP 1 LAST VOLTAGE 2.5V
J 2
(3325 2150);
DISPLAY 0.617021 (3325 2150);
PAINT SKYBLUE (3325 2150);
FORCEPROP 1 LAST MATERIAL ALUM
J 2
(3325 2100);
DISPLAY 0.617021 (3325 2100);
PAINT SKYBLUE (3325 2100);
FORCEPROP 1 LAST PART_NUMBER 699013-049
R 1
J 2
(3450 2325);
DISPLAY 0.617021 (3450 2325);
PAINT BLUE (3450 2325);
FORCEPROP 2 LAST SEC 1
J 0
(3335 2415);
DISPLAY 0.680851 (3335 2415);
PAINT MONO (3335 2415);
DISPLAY INVISIBLE (3335 2415);
FORCEPROP 2 LAST SEC_TYPE 3018
J 0
(3335 2415);
DISPLAY 1.021277 (3335 2415);
PAINT ORANGE (3335 2415);
DISPLAY INVISIBLE (3335 2415);
FORCEPROP 2 LAST CDS_LIB mstr_discrete
J 0
(3375 2200);
PAINT ORANGE (3375 2200);
DISPLAY INVISIBLE (3375 2200);
FORCEPROP 2 LAST ROOM PVCCIO_CPU1
J 2
(3325 2325);
PAINT MONO (3325 2325);
DISPLAY INVISIBLE (3325 2325);
FORCEPROP 1 LAST PATH I20
J 2
(3325 2350);
DISPLAY 0.978723 (3325 2350);
PAINT ORANGE (3325 2350);
DISPLAY INVISIBLE (3325 2350);
FORCEPROP 2 LAST CDS_LOCATION C4E7
J 2
(3325 2300);
DISPLAY 0.617021 (3325 2300);
PAINT AQUA (3325 2300);
DISPLAY INVISIBLE (3325 2300);
FORCEPROP 2 LAST BOM_COST PROC_VRD_PVCCIO_CPU1
J 2
(3325 2350);
PAINT MONO (3325 2350);
DISPLAY INVISIBLE (3325 2350);
FORCEADD CAPP..1
R 2
(2900 2200);
FORCEPROP 1 LASTPIN (2900 2300) $PN 1
J 2
(2890 2285);
DISPLAY 0.617021 (2890 2285);
PAINT WHITE (2890 2285);
FORCEPROP 1 LASTPIN (2900 2100) $PN 2
J 2
(2890 2085);
DISPLAY 0.617021 (2890 2085);
PAINT WHITE (2890 2085);
FORCEPROP 1 LAST TOLERANCE 20%
J 2
(2850 2200);
DISPLAY 0.617021 (2850 2200);
PAINT SKYBLUE (2850 2200);
FORCEPROP 1 LAST PACK_TYPE 3018
J 2
(2850 2050);
DISPLAY 0.617021 (2850 2050);
PAINT SKYBLUE (2850 2050);
FORCEPROP 1 LAST VOLTAGE 2.5V
J 2
(2850 2150);
DISPLAY 0.617021 (2850 2150);
PAINT SKYBLUE (2850 2150);
FORCEPROP 1 LAST MATERIAL ALUM
J 2
(2850 2100);
DISPLAY 0.617021 (2850 2100);
PAINT SKYBLUE (2850 2100);
FORCEPROP 1 LAST PART_NUMBER 699013-049
R 1
J 2
(2975 2325);
DISPLAY 0.617021 (2975 2325);
PAINT BLUE (2975 2325);
FORCEPROP 1 LAST LOCATION C6R12
J 2
(2850 2300);
DISPLAY 0.617021 (2850 2300);
PAINT AQUA (2850 2300);
FORCEPROP 1 LAST VALUE 470UF
J 2
(2850 2250);
DISPLAY 0.617021 (2850 2250);
PAINT SKYBLUE (2850 2250);
FORCEPROP 2 LAST ROOM PVCCIO_CPU1
J 2
(2850 2325);
PAINT MONO (2850 2325);
DISPLAY INVISIBLE (2850 2325);
FORCEPROP 1 LAST PATH I21
J 2
(2850 2350);
DISPLAY 0.978723 (2850 2350);
PAINT ORANGE (2850 2350);
DISPLAY INVISIBLE (2850 2350);
FORCEPROP 2 LAST SEC 1
J 0
(2860 2415);
DISPLAY 0.680851 (2860 2415);
PAINT MONO (2860 2415);
DISPLAY INVISIBLE (2860 2415);
FORCEPROP 2 LAST SEC_TYPE 3018
J 0
(2860 2415);
DISPLAY 1.021277 (2860 2415);
PAINT ORANGE (2860 2415);
DISPLAY INVISIBLE (2860 2415);
FORCEPROP 2 LAST BOM_COST PROC_VRD_PVCCIO_CPU1
J 2
(2850 2350);
PAINT MONO (2850 2350);
DISPLAY INVISIBLE (2850 2350);
FORCEPROP 2 LAST CDS_LOCATION C6R12
J 2
(2850 2300);
DISPLAY 0.617021 (2850 2300);
PAINT AQUA (2850 2300);
DISPLAY INVISIBLE (2850 2300);
FORCEPROP 2 LAST CDS_LIB mstr_discrete
J 0
(2900 2200);
PAINT ORANGE (2900 2200);
DISPLAY INVISIBLE (2900 2200);
FORCEADD CAPP..1
R 2
(2425 2200);
FORCEPROP 1 LAST LOCATION C6R5
J 2
(2375 2300);
DISPLAY 0.617021 (2375 2300);
PAINT AQUA (2375 2300);
FORCEPROP 1 LASTPIN (2425 2300) $PN 1
J 2
(2415 2285);
DISPLAY 0.617021 (2415 2285);
PAINT WHITE (2415 2285);
FORCEPROP 1 LASTPIN (2425 2100) $PN 2
J 2
(2415 2085);
DISPLAY 0.617021 (2415 2085);
PAINT WHITE (2415 2085);
FORCEPROP 1 LAST TOLERANCE 20%
J 2
(2375 2200);
DISPLAY 0.617021 (2375 2200);
PAINT SKYBLUE (2375 2200);
FORCEPROP 1 LAST PACK_TYPE 3018
J 2
(2375 2050);
DISPLAY 0.617021 (2375 2050);
PAINT SKYBLUE (2375 2050);
FORCEPROP 1 LAST VOLTAGE 2.5V
J 2
(2375 2150);
DISPLAY 0.617021 (2375 2150);
PAINT SKYBLUE (2375 2150);
FORCEPROP 1 LAST MATERIAL ALUM
J 2
(2375 2100);
DISPLAY 0.617021 (2375 2100);
PAINT SKYBLUE (2375 2100);
FORCEPROP 1 LAST VALUE 470UF
J 2
(2375 2250);
DISPLAY 0.617021 (2375 2250);
PAINT SKYBLUE (2375 2250);
FORCEPROP 1 LAST PART_NUMBER 699013-049
R 1
J 2
(2500 2325);
DISPLAY 0.617021 (2500 2325);
PAINT BLUE (2500 2325);
FORCEPROP 2 LAST ROOM PVCCIO_CPU1
J 2
(2375 2325);
PAINT MONO (2375 2325);
DISPLAY INVISIBLE (2375 2325);
FORCEPROP 1 LAST PATH I24
J 2
(2375 2350);
DISPLAY 0.978723 (2375 2350);
PAINT ORANGE (2375 2350);
DISPLAY INVISIBLE (2375 2350);
FORCEPROP 2 LAST SEC 1
J 0
(2385 2415);
DISPLAY 0.680851 (2385 2415);
PAINT MONO (2385 2415);
DISPLAY INVISIBLE (2385 2415);
FORCEPROP 2 LAST BOM_COST PROC_VRD_PVCCIO_CPU1
J 2
(2375 2350);
PAINT MONO (2375 2350);
DISPLAY INVISIBLE (2375 2350);
FORCEPROP 2 LAST SEC_TYPE 3018
J 0
(2385 2415);
DISPLAY 1.021277 (2385 2415);
PAINT ORANGE (2385 2415);
DISPLAY INVISIBLE (2385 2415);
FORCEPROP 2 LAST CDS_LOCATION C6R5
J 2
(2375 2300);
DISPLAY 0.617021 (2375 2300);
PAINT AQUA (2375 2300);
DISPLAY INVISIBLE (2375 2300);
FORCEPROP 2 LAST CDS_LIB mstr_discrete
J 0
(2425 2200);
PAINT ORANGE (2425 2200);
DISPLAY INVISIBLE (2425 2200);
FORCEADD GND..1
(1275 1650);
FORCEPROP 3 LASTPIN (1275 1700) SIG_NAME GND\g
J 0
(1285 1710);
DISPLAY 0.659574 (1285 1710);
PAINT MONO (1285 1710);
DISPLAY INVISIBLE (1285 1710);
FORCEPROP 2 LAST CDS_LIB mstr_symbols
J 0
(1275 1650);
DISPLAY 0.723404 (1275 1650);
PAINT ORANGE (1275 1650);
DISPLAY INVISIBLE (1275 1650);
FORCEPROP 1 LAST SIZE 1B
J 0
(1350 1600);
DISPLAY 0.553191 (1350 1600);
PAINT ORANGE (1350 1600);
DISPLAY INVISIBLE (1350 1600);
FORCEPROP 1 LAST BODY_TYPE PLUMBING
J 0
(1230 1607);
DISPLAY 0.340426 (1230 1607);
PAINT GREEN (1230 1607);
DISPLAY INVISIBLE (1230 1607);
FORCEPROP 1 LAST PATH I28
J 0
(1350 1650);
DISPLAY 0.872340 (1350 1650);
PAINT AQUA (1350 1650);
DISPLAY INVISIBLE (1350 1650);
FORCEPROP 1 LAST VOLTAGE 0.0V
J 0
(1230 1607);
DISPLAY 0.340426 (1230 1607);
PAINT SKYBLUE (1230 1607);
DISPLAY INVISIBLE (1230 1607);
FORCEPROP 2 LAST BOM_COST PROC_VRD_PVCCIO_CPU1
J 0
(925 1725);
DISPLAY 0.617021 (925 1725);
PAINT ORANGE (925 1725);
DISPLAY INVISIBLE (925 1725);
FORCEPROP 2 LAST ROOM PVCCIO_CPU1
J 0
(975 1725);
DISPLAY 0.723404 (975 1725);
PAINT ORANGE (975 1725);
DISPLAY INVISIBLE (975 1725);
FORCEPROP 1 LAST HDL_POWER GND
J 0
(1275 1800);
DISPLAY 0.553191 (1275 1800);
PAINT GREEN (1275 1800);
DISPLAY INVISIBLE (1275 1800);
FORCEADD CAP..1
R 2
(1275 1900);
FORCEPROP 1 LAST MATERIAL X5R
J 2
(1225 1800);
DISPLAY 0.617021 (1225 1800);
PAINT SKYBLUE (1225 1800);
FORCEPROP 1 LAST TOLERANCE 20%
J 2
(1225 1850);
DISPLAY 0.617021 (1225 1850);
PAINT SKYBLUE (1225 1850);
FORCEPROP 1 LASTPIN (1275 1800) $PN 2
J 2
(1265 1780);
DISPLAY 0.617021 (1265 1780);
PAINT WHITE (1265 1780);
FORCEPROP 1 LAST VOLTAGE 16V
J 2
(1225 1900);
DISPLAY 0.617021 (1225 1900);
PAINT SKYBLUE (1225 1900);
FORCEPROP 1 LAST PACK_TYPE 1210
J 2
(1250 1750);
DISPLAY 0.617021 (1250 1750);
PAINT SKYBLUE (1250 1750);
FORCEPROP 1 LAST VALUE 100UF
J 2
(1225 1950);
DISPLAY 0.617021 (1225 1950);
PAINT SKYBLUE (1225 1950);
FORCEPROP 1 LAST LOCATION C4E8
J 2
(1225 2000);
DISPLAY 0.617021 (1225 2000);
PAINT AQUA (1225 2000);
FORCEPROP 1 LASTPIN (1275 2000) $PN 1
J 2
(1265 1980);
DISPLAY 0.617021 (1265 1980);
PAINT WHITE (1265 1980);
FORCEPROP 1 LAST PART_NUMBER 644066-127
J 2
(1254 1704);
DISPLAY 0.617021 (1254 1704);
PAINT BLUE (1254 1704);
FORCEPROP 2 LAST CDS_LIB mstr_discrete
J 0
(1275 1900);
DISPLAY 0.723404 (1275 1900);
PAINT ORANGE (1275 1900);
DISPLAY INVISIBLE (1275 1900);
FORCEPROP 2 LAST CDS_LOCATION C4E8
J 2
(1225 2000);
DISPLAY 0.617021 (1225 2000);
PAINT AQUA (1225 2000);
DISPLAY INVISIBLE (1225 2000);
FORCEPROP 2 LAST BOM_COST PROC_VRD_PVCCIO_CPU1
J 0
(1225 2050);
DISPLAY 0.723404 (1225 2050);
PAINT ORANGE (1225 2050);
DISPLAY INVISIBLE (1225 2050);
FORCEPROP 1 LAST PATH I29
J 2
(1225 2050);
DISPLAY 0.978723 (1225 2050);
PAINT WHITE (1225 2050);
DISPLAY INVISIBLE (1225 2050);
FORCEPROP 2 LAST ROOM PVCCIO_CPU1
J 0
(1225 2050);
DISPLAY 0.723404 (1225 2050);
PAINT ORANGE (1225 2050);
DISPLAY INVISIBLE (1225 2050);
FORCEPROP 2 LAST SEC_TYPE 1210
J 0
(1225 2096);
DISPLAY 1.021277 (1225 2096);
PAINT ORANGE (1225 2096);
DISPLAY INVISIBLE (1225 2096);
FORCEPROP 2 LAST SEC 1
J 0
(1225 2096);
DISPLAY 0.680851 (1225 2096);
PAINT MONO (1225 2096);
DISPLAY INVISIBLE (1225 2096);
FORCEADD PVCCIO_CPU1..1
(3375 2550);
FORCEPROP 3 LASTPIN (3375 2500) SIG_NAME PVCCIO_CPU1\g
J 0
(3385 2510);
DISPLAY 0.659574 (3385 2510);
PAINT MONO (3385 2510);
DISPLAY INVISIBLE (3385 2510);
FORCEPROP 1 LAST HDL_POWER PVCCIO_CPU1
J 1
(3375 2600);
DISPLAY 0.872340 (3375 2600);
PAINT GREEN (3375 2600);
DISPLAY INVISIBLE (3375 2600);
FORCEPROP 1 LAST PATH I3
J 0
(3425 2575);
DISPLAY 0.872340 (3425 2575);
PAINT AQUA (3425 2575);
DISPLAY INVISIBLE (3425 2575);
FORCEPROP 2 LAST CDS_LIB mstr_symbols
J 0
(3375 2550);
PAINT ORANGE (3375 2550);
DISPLAY INVISIBLE (3375 2550);
FORCEPROP 1 LAST BODY_TYPE PLUMBING
J 0
(3330 2507);
DISPLAY 0.340426 (3330 2507);
PAINT GREEN (3330 2507);
DISPLAY INVISIBLE (3330 2507);
FORCEPROP 1 LAST VOLTAGE 1.1V
J 0
(3330 2507);
DISPLAY 0.340426 (3330 2507);
PAINT SKYBLUE (3330 2507);
DISPLAY INVISIBLE (3330 2507);
FORCEADD UNIVERSAL_POWER..1
(1650 2225);
FORCEPROP 3 LASTPIN (1650 2175) SIG_NAME VR_FET_SW_P12V_STBY_PVCCIN_CPU0\g
J 0
(1660 2185);
DISPLAY 0.659574 (1660 2185);
PAINT MONO (1660 2185);
DISPLAY INVISIBLE (1660 2185);
FORCEPROP 1 LAST HDL_POWER VR_FET_SW_P12V_STBY_PVCCIN_CPU0
J 1
(1750 2275);
DISPLAY 0.617021 (1750 2275);
PAINT GREEN (1750 2275);
FORCEPROP 2 LAST CDS_LIB mstr_symbols
J 0
(1650 2225);
PAINT ORANGE (1650 2225);
DISPLAY INVISIBLE (1650 2225);
FORCEPROP 1 LAST PATH I30
J 0
(1700 2250);
DISPLAY 0.872340 (1700 2250);
PAINT AQUA (1700 2250);
DISPLAY INVISIBLE (1700 2250);
FORCEADD CAP..1
(700 1875);
FORCEPROP 1 LAST PART_NUMBER 644066-127
J 0
(750 1725);
DISPLAY 0.617021 (750 1725);
PAINT BLUE (750 1725);
FORCEPROP 1 LAST PACK_TYPE 1210
J 0
(750 1675);
DISPLAY 0.617021 (750 1675);
PAINT SKYBLUE (750 1675);
FORCEPROP 1 LASTPIN (700 1775) $PN 2
J 0
(710 1755);
DISPLAY 0.617021 (710 1755);
PAINT WHITE (710 1755);
FORCEPROP 1 LASTPIN (700 1975) $PN 1
J 0
(710 1955);
DISPLAY 0.617021 (710 1955);
PAINT WHITE (710 1955);
FORCEPROP 1 LAST TOLERANCE 20%
J 0
(750 1825);
DISPLAY 0.617021 (750 1825);
PAINT SKYBLUE (750 1825);
FORCEPROP 1 LAST MATERIAL X5R
J 0
(750 1775);
DISPLAY 0.617021 (750 1775);
PAINT SKYBLUE (750 1775);
FORCEPROP 1 LAST VOLTAGE 16V
J 0
(750 1875);
DISPLAY 0.617021 (750 1875);
PAINT SKYBLUE (750 1875);
FORCEPROP 1 LAST VALUE 100UF
J 0
(750 1925);
DISPLAY 0.617021 (750 1925);
PAINT SKYBLUE (750 1925);
FORCEPROP 1 LAST LOCATION C4E14
J 0
(750 1975);
DISPLAY 0.617021 (750 1975);
PAINT AQUA (750 1975);
FORCEPROP 2 LAST CDS_LIB mstr_discrete
J 0
(700 1875);
PAINT ORANGE (700 1875);
DISPLAY INVISIBLE (700 1875);
FORCEPROP 2 LAST CDS_LOCATION C4E14
J 0
(750 1975);
DISPLAY 0.617021 (750 1975);
PAINT AQUA (750 1975);
DISPLAY INVISIBLE (750 1975);
FORCEPROP 2 LAST SEC 1
J 0
(750 2071);
DISPLAY 0.680851 (750 2071);
PAINT MONO (750 2071);
DISPLAY INVISIBLE (750 2071);
FORCEPROP 2 LAST SEC_TYPE 1210
J 0
(750 2071);
DISPLAY 1.021277 (750 2071);
PAINT ORANGE (750 2071);
DISPLAY INVISIBLE (750 2071);
FORCEPROP 2 LAST BOM_COST PROC_VRD_PVCCIO_CPU1
J 0
(750 2025);
DISPLAY 0.829787 (750 2025);
PAINT PURPLE (750 2025);
DISPLAY INVISIBLE (750 2025);
FORCEPROP 1 LAST PATH I31
J 0
(750 2025);
DISPLAY 0.978723 (750 2025);
PAINT WHITE (750 2025);
DISPLAY INVISIBLE (750 2025);
FORCEPROP 2 LAST ROOM PVCCIO_CPU1
J 0
(750 2025);
DISPLAY 0.829787 (750 2025);
PAINT ORANGE (750 2025);
DISPLAY INVISIBLE (750 2025);
FORCEADD GND..1
(700 1650);
FORCEPROP 3 LASTPIN (700 1700) SIG_NAME GND\g
J 0
(710 1710);
DISPLAY 0.659574 (710 1710);
PAINT MONO (710 1710);
DISPLAY INVISIBLE (710 1710);
FORCEPROP 2 LAST CDS_LIB mstr_symbols
J 0
(700 1650);
PAINT MONO (700 1650);
DISPLAY INVISIBLE (700 1650);
FORCEPROP 1 LAST SIZE 1B
J 0
(775 1600);
DISPLAY 0.553191 (775 1600);
PAINT ORANGE (775 1600);
DISPLAY INVISIBLE (775 1600);
FORCEPROP 1 LAST BODY_TYPE PLUMBING
J 0
(655 1607);
DISPLAY 0.340426 (655 1607);
PAINT GREEN (655 1607);
DISPLAY INVISIBLE (655 1607);
FORCEPROP 1 LAST PATH I32
J 0
(775 1650);
DISPLAY 0.872340 (775 1650);
PAINT AQUA (775 1650);
DISPLAY INVISIBLE (775 1650);
FORCEPROP 1 LAST VOLTAGE 0.0V
J 0
(655 1607);
DISPLAY 0.340426 (655 1607);
PAINT SKYBLUE (655 1607);
DISPLAY INVISIBLE (655 1607);
FORCEPROP 2 LAST ROOM PVCCIO_CPU1
J 0
(400 1725);
DISPLAY 0.723404 (400 1725);
PAINT ORANGE (400 1725);
DISPLAY INVISIBLE (400 1725);
FORCEPROP 2 LAST BOM_COST PROC_VRD_PVCCIO_CPU1
J 0
(350 1725);
DISPLAY 0.617021 (350 1725);
PAINT ORANGE (350 1725);
DISPLAY INVISIBLE (350 1725);
FORCEPROP 1 LAST HDL_POWER GND
J 0
(700 1800);
DISPLAY 0.553191 (700 1800);
PAINT GREEN (700 1800);
DISPLAY INVISIBLE (700 1800);
FORCEADD OFFPAGE..2
(2500 3675);
FORCEPROP 2 LAST $XR0 213 
J 0
(2689 3675);
DISPLAY 0.638298 (2689 3675);
PAINT MONO (2689 3675);
FORCEPROP 1 LAST COMMENT_BODY TRUE
J 0
(2455 3580);
DISPLAY 2.787234 (2455 3580);
PAINT PEACH (2455 3580);
DISPLAY INVISIBLE (2455 3580);
FORCEPROP 2 LAST CDS_LIB mstr_standard
J 0
(2500 3675);
DISPLAY 1.617021 (2500 3675);
PAINT ORANGE (2500 3675);
DISPLAY INVISIBLE (2500 3675);
FORCEPROP 2 LAST ROOM PVCCIO_CPU1
J 0
(2100 3750);
DISPLAY 3.127660 (2100 3750);
PAINT WHITE (2100 3750);
DISPLAY INVISIBLE (2100 3750);
FORCEPROP 1 LAST OFFPAGE TRUE
J 0
(2825 3550);
PAINT GREEN (2825 3550);
DISPLAY INVISIBLE (2825 3550);
FORCEPROP 2 LAST BOM_COST PROC_VRD_PVCCIO_CPU1
J 0
(2700 3725);
DISPLAY 2.340426 (2700 3725);
PAINT WHITE (2700 3725);
DISPLAY INVISIBLE (2700 3725);
FORCEPROP 2 LAST PATH I58
J 0
(2675 3750);
DISPLAY 1.021277 (2675 3750);
PAINT ORANGE (2675 3750);
DISPLAY INVISIBLE (2675 3750);
FORCEADD OFFPAGE..2
(2650 4025);
FORCEPROP 2 LAST $XR0 213 
J 0
(2839 4025);
DISPLAY 0.638298 (2839 4025);
PAINT MONO (2839 4025);
FORCEPROP 2 LAST PATH I59
J 0
(2825 4100);
DISPLAY 1.021277 (2825 4100);
PAINT ORANGE (2825 4100);
DISPLAY INVISIBLE (2825 4100);
FORCEPROP 2 LAST ROOM PVCCIO_CPU1
J 0
(2250 4100);
DISPLAY 3.127660 (2250 4100);
PAINT WHITE (2250 4100);
DISPLAY INVISIBLE (2250 4100);
FORCEPROP 2 LAST BOM_COST PROC_VRD_PVCCIO_CPU1
J 0
(2850 4075);
DISPLAY 2.340426 (2850 4075);
PAINT WHITE (2850 4075);
DISPLAY INVISIBLE (2850 4075);
FORCEPROP 1 LAST OFFPAGE TRUE
J 0
(2975 3900);
PAINT GREEN (2975 3900);
DISPLAY INVISIBLE (2975 3900);
FORCEPROP 1 LAST COMMENT_BODY TRUE
J 0
(2605 3930);
DISPLAY 2.787234 (2605 3930);
PAINT PEACH (2605 3930);
DISPLAY INVISIBLE (2605 3930);
FORCEPROP 2 LAST CDS_LIB mstr_standard
J 0
(2650 4025);
DISPLAY 1.617021 (2650 4025);
PAINT ORANGE (2650 4025);
DISPLAY INVISIBLE (2650 4025);
FORCEADD GND..1
(3375 1900);
FORCEPROP 3 LASTPIN (3375 1950) SIG_NAME GND\g
J 0
(3385 1960);
DISPLAY 0.659574 (3385 1960);
PAINT MONO (3385 1960);
DISPLAY INVISIBLE (3385 1960);
FORCEPROP 1 LAST HDL_POWER GND
J 0
(3375 2050);
DISPLAY 0.638298 (3375 2050);
PAINT GREEN (3375 2050);
DISPLAY INVISIBLE (3375 2050);
FORCEPROP 1 LAST VOLTAGE 0
J 0
(3375 1900);
DISPLAY 0.723404 (3375 1900);
PAINT SKYBLUE (3375 1900);
DISPLAY INVISIBLE (3375 1900);
FORCEPROP 2 LAST CDS_LIB mstr_symbols
J 0
(3375 1900);
DISPLAY 0.723404 (3375 1900);
PAINT ORANGE (3375 1900);
DISPLAY INVISIBLE (3375 1900);
FORCEPROP 1 LAST PATH I6
J 0
(3450 1900);
DISPLAY 0.872340 (3450 1900);
PAINT AQUA (3450 1900);
DISPLAY INVISIBLE (3450 1900);
FORCEPROP 1 LAST SIZE 1B
J 0
(3450 1850);
DISPLAY 0.638298 (3450 1850);
PAINT GREEN (3450 1850);
DISPLAY INVISIBLE (3450 1850);
FORCEPROP 1 LAST BODY_TYPE PLUMBING
J 0
(3330 1857);
DISPLAY 0.340426 (3330 1857);
PAINT GREEN (3330 1857);
DISPLAY INVISIBLE (3330 1857);
FORCEPROP 2 LAST ROOM PVCCIO_CPU1
J 0
(3075 1975);
DISPLAY 0.723404 (3075 1975);
PAINT ORANGE (3075 1975);
DISPLAY INVISIBLE (3075 1975);
FORCEPROP 2 LAST BOM_COST PROC_VRD_PVCCIO_CPU1
J 0
(2875 1975);
DISPLAY 0.723404 (2875 1975);
PAINT ORANGE (2875 1975);
DISPLAY INVISIBLE (2875 1975);
FORCEADD OFFPAGE..2
(2625 4375);
FORCEPROP 2 LAST $XR0 213 
J 0
(2814 4375);
DISPLAY 0.638298 (2814 4375);
PAINT MONO (2814 4375);
FORCEPROP 1 LAST OFFPAGE TRUE
J 0
(2950 4250);
PAINT GREEN (2950 4250);
DISPLAY INVISIBLE (2950 4250);
FORCEPROP 2 LAST BOM_COST PROC_VRD_PVCCIO_CPU1
J 0
(2825 4425);
DISPLAY 2.340426 (2825 4425);
PAINT WHITE (2825 4425);
DISPLAY INVISIBLE (2825 4425);
FORCEPROP 2 LAST PATH I60
J 0
(2800 4450);
DISPLAY 1.021277 (2800 4450);
PAINT ORANGE (2800 4450);
DISPLAY INVISIBLE (2800 4450);
FORCEPROP 2 LAST CDS_LIB mstr_standard
J 0
(2625 4375);
DISPLAY 1.617021 (2625 4375);
PAINT ORANGE (2625 4375);
DISPLAY INVISIBLE (2625 4375);
FORCEPROP 1 LAST COMMENT_BODY TRUE
J 0
(2580 4280);
DISPLAY 2.787234 (2580 4280);
PAINT PEACH (2580 4280);
DISPLAY INVISIBLE (2580 4280);
FORCEPROP 2 LAST ROOM PVCCIO_CPU1
J 0
(2225 4450);
DISPLAY 3.127660 (2225 4450);
PAINT WHITE (2225 4450);
DISPLAY INVISIBLE (2225 4450);
FORCEADD PVCCIO_CPU1..1
(3875 3275);
FORCEPROP 3 LASTPIN (3875 3225) SIG_NAME PVCCIO_CPU1\g
J 0
(3885 3235);
DISPLAY 0.659574 (3885 3235);
PAINT MONO (3885 3235);
DISPLAY INVISIBLE (3885 3235);
FORCEPROP 2 LAST BOM_COST PROC_VRD_PVCCIO_CPU1
J 0
(3875 3375);
DISPLAY 2.340426 (3875 3375);
PAINT WHITE (3875 3375);
DISPLAY INVISIBLE (3875 3375);
FORCEPROP 2 LAST ROOM PVCCIO_CPU1
J 0
(3875 3375);
DISPLAY 3.127660 (3875 3375);
PAINT WHITE (3875 3375);
DISPLAY INVISIBLE (3875 3375);
FORCEPROP 1 LAST PATH I64
J 0
(3925 3300);
DISPLAY 0.872340 (3925 3300);
PAINT AQUA (3925 3300);
DISPLAY INVISIBLE (3925 3300);
FORCEPROP 1 LAST HDL_POWER PVCCIO_CPU1
J 1
(3875 3325);
DISPLAY 0.872340 (3875 3325);
PAINT GREEN (3875 3325);
DISPLAY INVISIBLE (3875 3325);
FORCEPROP 2 LAST CDS_LIB mstr_symbols
J 0
(3875 3275);
PAINT ORANGE (3875 3275);
DISPLAY INVISIBLE (3875 3275);
FORCEPROP 1 LAST VOLTAGE 1.1V
J 0
(3830 3232);
DISPLAY 0.340426 (3830 3232);
PAINT SKYBLUE (3830 3232);
DISPLAY INVISIBLE (3830 3232);
FORCEPROP 1 LAST BODY_TYPE PLUMBING
J 0
(3830 3232);
DISPLAY 0.340426 (3830 3232);
PAINT GREEN (3830 3232);
DISPLAY INVISIBLE (3830 3232);
FORCEADD CAP_A..1
(3125 3000);
FORCEPROP 1 LAST LOCATION C7R1
J 0
(3175 3100);
DISPLAY 0.617021 (3175 3100);
PAINT AQUA (3175 3100);
FORCEPROP 1 LASTPIN (3125 3100) $PN 1
J 0
(3135 3080);
DISPLAY 0.617021 (3135 3080);
PAINT WHITE (3135 3080);
FORCEPROP 1 LAST VALUE 22.0UF
J 0
(3175 3050);
DISPLAY 0.617021 (3175 3050);
PAINT SKYBLUE (3175 3050);
FORCEPROP 1 LAST PART_NUMBER E15431-004
J 0
(3175 2850);
DISPLAY 0.617021 (3175 2850);
PAINT BLUE (3175 2850);
FORCEPROP 1 LAST TOLERANCE 20%
J 0
(3175 2950);
DISPLAY 0.617021 (3175 2950);
PAINT SKYBLUE (3175 2950);
FORCEPROP 1 LASTPIN (3125 2900) $PN 2
J 0
(3135 2880);
DISPLAY 0.617021 (3135 2880);
PAINT WHITE (3135 2880);
FORCEPROP 1 LAST MATERIAL X6S
J 0
(3175 2900);
DISPLAY 0.617021 (3175 2900);
PAINT SKYBLUE (3175 2900);
FORCEPROP 1 LAST VOLTAGE 4V
J 0
(3175 3000);
DISPLAY 0.617021 (3175 3000);
PAINT SKYBLUE (3175 3000);
FORCEPROP 1 LAST PACK_TYPE 0603V
J 0
(3175 2800);
DISPLAY 0.617021 (3175 2800);
PAINT SKYBLUE (3175 2800);
FORCEPROP 2 LAST ROOM PVCCIO_CPU1
J 0
(3175 3150);
DISPLAY 2.340426 (3175 3150);
PAINT WHITE (3175 3150);
DISPLAY INVISIBLE (3175 3150);
FORCEPROP 2 LAST SEC 1
J 0
(3180 3200);
DISPLAY 1.106383 (3180 3200);
PAINT MONO (3180 3200);
DISPLAY INVISIBLE (3180 3200);
FORCEPROP 2 LAST SEC_TYPE 0603V
J 0
(3180 3200);
DISPLAY 1.659574 (3180 3200);
PAINT ORANGE (3180 3200);
DISPLAY INVISIBLE (3180 3200);
FORCEPROP 2 LAST BOM_COST PROC_VRD_PVCCIO_CPU1
J 0
(3175 3150);
DISPLAY 2.340426 (3175 3150);
PAINT WHITE (3175 3150);
DISPLAY INVISIBLE (3175 3150);
FORCEPROP 1 LAST PATH I65
J 0
(3175 3150);
DISPLAY 0.978723 (3175 3150);
PAINT WHITE (3175 3150);
DISPLAY INVISIBLE (3175 3150);
FORCEPROP 2 LAST CDS_SEC 1
J 0
(3175 3150);
PAINT ORANGE (3175 3150);
DISPLAY INVISIBLE (3175 3150);
FORCEPROP 2 LAST CDS_LOCATION C7R1
J 0
(3175 3100);
DISPLAY 0.617021 (3175 3100);
PAINT AQUA (3175 3100);
DISPLAY INVISIBLE (3175 3100);
FORCEPROP 2 LAST CDS_LIB dev_discrete
J 0
(3125 3000);
PAINT ORANGE (3125 3000);
DISPLAY INVISIBLE (3125 3000);
FORCEADD GND..1
(3875 2675);
FORCEPROP 3 LASTPIN (3875 2725) SIG_NAME GND\g
J 0
(3885 2735);
DISPLAY 0.659574 (3885 2735);
PAINT MONO (3885 2735);
DISPLAY INVISIBLE (3885 2735);
FORCEPROP 1 LAST HDL_POWER GND
J 0
(3875 2825);
DISPLAY 2.787234 (3875 2825);
PAINT GREEN (3875 2825);
DISPLAY INVISIBLE (3875 2825);
FORCEPROP 1 LAST PATH I66
J 0
(3950 2675);
DISPLAY 0.872340 (3950 2675);
PAINT AQUA (3950 2675);
DISPLAY INVISIBLE (3950 2675);
FORCEPROP 2 LAST CDS_LIB mstr_symbols
J 0
(3875 2675);
DISPLAY 1.617021 (3875 2675);
PAINT ORANGE (3875 2675);
DISPLAY INVISIBLE (3875 2675);
FORCEPROP 1 LAST SIZE 1B
J 0
(3950 2625);
DISPLAY 2.787234 (3950 2625);
PAINT GREEN (3950 2625);
DISPLAY INVISIBLE (3950 2625);
FORCEPROP 1 LAST VOLTAGE 0.0V
J 0
(3830 2632);
DISPLAY 0.340426 (3830 2632);
PAINT SKYBLUE (3830 2632);
DISPLAY INVISIBLE (3830 2632);
FORCEPROP 1 LAST BODY_TYPE PLUMBING
J 0
(3830 2632);
DISPLAY 0.340426 (3830 2632);
PAINT GREEN (3830 2632);
DISPLAY INVISIBLE (3830 2632);
FORCEPROP 2 LAST BOM_COST PROC_VRD_PVCCIO_CPU1
J 0
(3500 2750);
DISPLAY 2.340426 (3500 2750);
PAINT WHITE (3500 2750);
DISPLAY INVISIBLE (3500 2750);
FORCEPROP 2 LAST ROOM PVCCIO_CPU1
J 0
(3325 2750);
DISPLAY 3.127660 (3325 2750);
PAINT WHITE (3325 2750);
DISPLAY INVISIBLE (3325 2750);
FORCEADD INDUCTOR..1
(2550 3175);
FORCEPROP 1 LAST PART_NUMBER D92183-021
J 0
(2450 3275);
DISPLAY 0.617021 (2450 3275);
PAINT BLUE (2450 3275);
FORCEPROP 1 LAST PACK_TYPE SM
J 0
(2490 3040);
DISPLAY 0.617021 (2490 3040);
PAINT SKYBLUE (2490 3040);
FORCEPROP 1 LAST VALUE 150NH
J 2
(2545 3090);
DISPLAY 0.617021 (2545 3090);
PAINT SKYBLUE (2545 3090);
FORCEPROP 1 LAST LOCATION L4E2
J 0
(2450 3225);
DISPLAY 0.617021 (2450 3225);
PAINT AQUA (2450 3225);
FORCEPROP 1 LAST MATERIAL IND
J 0
(2565 3090);
DISPLAY 0.617021 (2565 3090);
PAINT SKYBLUE (2565 3090);
FORCEPROP 1 LASTPIN (2650 3175) $PN 2
J 2
(2660 3185);
DISPLAY 0.702128 (2660 3185);
PAINT WHITE (2660 3185);
DISPLAY INVISIBLE (2660 3185);
FORCEPROP 2 LAST $SEC 1
J 0
(2450 3375);
PAINT MONO (2450 3375);
DISPLAY INVISIBLE (2450 3375);
FORCEPROP 2 LAST CDS_SEC 1
J 0
(2450 3375);
PAINT MONO (2450 3375);
DISPLAY INVISIBLE (2450 3375);
FORCEPROP 2 LAST ROOM PVCCIO_CPU1
J 0
(2450 3275);
DISPLAY 2.212766 (2450 3275);
PAINT WHITE (2450 3275);
DISPLAY INVISIBLE (2450 3275);
FORCEPROP 1 LAST PATH I67
J 0
(2450 3325);
DISPLAY 0.978723 (2450 3325);
PAINT ORANGE (2450 3325);
DISPLAY INVISIBLE (2450 3325);
FORCEPROP 2 LAST CDS_LIB mstr_discrete
J 0
(2550 3175);
PAINT ORANGE (2550 3175);
DISPLAY INVISIBLE (2550 3175);
FORCEPROP 2 LAST CDS_LOCATION L4E2
J 0
(2450 3225);
DISPLAY 0.617021 (2450 3225);
PAINT AQUA (2450 3225);
DISPLAY INVISIBLE (2450 3225);
FORCEPROP 1 LASTPIN (2450 3175) $PN 1
J 0
(2450 3185);
DISPLAY 0.702128 (2450 3185);
PAINT WHITE (2450 3185);
DISPLAY INVISIBLE (2450 3185);
FORCEADD GND..1
(1500 2800);
FORCEPROP 3 LASTPIN (1500 2850) SIG_NAME GND\g
J 0
(1510 2860);
DISPLAY 0.659574 (1510 2860);
PAINT MONO (1510 2860);
DISPLAY INVISIBLE (1510 2860);
FORCEPROP 1 LAST PATH I68
J 0
(1575 2800);
DISPLAY 0.872340 (1575 2800);
PAINT AQUA (1575 2800);
DISPLAY INVISIBLE (1575 2800);
FORCEPROP 1 LAST SIZE 1B
J 0
(1575 2750);
DISPLAY 2.787234 (1575 2750);
PAINT GREEN (1575 2750);
DISPLAY INVISIBLE (1575 2750);
FORCEPROP 1 LAST HDL_POWER GND
J 0
(1500 2950);
DISPLAY 2.787234 (1500 2950);
PAINT GREEN (1500 2950);
DISPLAY INVISIBLE (1500 2950);
FORCEPROP 2 LAST CDS_LIB mstr_symbols
J 0
(1500 2800);
DISPLAY 1.617021 (1500 2800);
PAINT ORANGE (1500 2800);
DISPLAY INVISIBLE (1500 2800);
FORCEPROP 1 LAST VOLTAGE 0.0V
J 0
(1455 2757);
DISPLAY 0.340426 (1455 2757);
PAINT SKYBLUE (1455 2757);
DISPLAY INVISIBLE (1455 2757);
FORCEPROP 1 LAST BODY_TYPE PLUMBING
J 0
(1455 2757);
DISPLAY 0.340426 (1455 2757);
PAINT GREEN (1455 2757);
DISPLAY INVISIBLE (1455 2757);
FORCEPROP 2 LAST BOM_COST PROC_VRD_PVCCIO_CPU1
J 0
(1125 2875);
DISPLAY 2.340426 (1125 2875);
PAINT WHITE (1125 2875);
DISPLAY INVISIBLE (1125 2875);
FORCEPROP 2 LAST ROOM PVCCIO_CPU1
J 0
(950 2875);
DISPLAY 3.127660 (950 2875);
PAINT WHITE (950 2875);
DISPLAY INVISIBLE (950 2875);
FORCEADD RES..1
(-1875 4300);
FORCEPROP 1 LAST WATTAGE 1/16W
J 2
(-1850 4125);
DISPLAY 0.617021 (-1850 4125);
PAINT SKYBLUE (-1850 4125);
FORCEPROP 1 LAST PART_NUMBER G21796-090
J 0
(-2000 4225);
DISPLAY 0.617021 (-2000 4225);
PAINT BLUE (-2000 4225);
FORCEPROP 1 LAST PACK_TYPE 0402
J 0
(-1825 4175);
DISPLAY 0.617021 (-1825 4175);
PAINT SKYBLUE (-1825 4175);
FORCEPROP 1 LAST MATERIAL CHIP
J 0
(-1800 4125);
DISPLAY 0.617021 (-1800 4125);
PAINT SKYBLUE (-1800 4125);
FORCEPROP 1 LASTPIN (-1775 4300) $PN 2
J 0
(-1813 4312);
DISPLAY 0.617021 (-1813 4312);
PAINT WHITE (-1813 4312);
FORCEPROP 1 LAST LOCATION R6R5
J 0
(-1925 4350);
DISPLAY 0.617021 (-1925 4350);
PAINT AQUA (-1925 4350);
FORCEPROP 1 LASTPIN (-1975 4300) $PN 1
J 0
(-1963 4312);
DISPLAY 0.617021 (-1963 4312);
PAINT WHITE (-1963 4312);
FORCEPROP 1 LAST TOLERANCE 1%
J 0
(-1925 4175);
DISPLAY 0.617021 (-1925 4175);
PAINT SKYBLUE (-1925 4175);
FORCEPROP 1 LAST VALUE 1.0
J 2
(-1975 4175);
DISPLAY 0.617021 (-1975 4175);
PAINT SKYBLUE (-1975 4175);
FORCEPROP 2 LAST ROOM PVCCIO_CPU1
J 0
(-1925 4400);
DISPLAY 2.212766 (-1925 4400);
PAINT WHITE (-1925 4400);
DISPLAY INVISIBLE (-1925 4400);
FORCEPROP 1 LAST PATH I71
J 0
(-1925 4450);
DISPLAY 0.978723 (-1925 4450);
PAINT WHITE (-1925 4450);
DISPLAY INVISIBLE (-1925 4450);
FORCEPROP 2 LAST SEC_TYPE 0402
J 0
(-1925 4500);
DISPLAY 1.659574 (-1925 4500);
PAINT ORANGE (-1925 4500);
DISPLAY INVISIBLE (-1925 4500);
FORCEPROP 2 LAST SEC 1
J 0
(-1925 4500);
DISPLAY 1.106383 (-1925 4500);
PAINT MONO (-1925 4500);
DISPLAY INVISIBLE (-1925 4500);
FORCEPROP 2 LAST CDS_LOCATION R6R5
J 0
(-1925 4350);
DISPLAY 0.617021 (-1925 4350);
PAINT AQUA (-1925 4350);
DISPLAY INVISIBLE (-1925 4350);
FORCEPROP 2 LAST CDS_LIB mstr_discrete
J 0
(-1875 4300);
DISPLAY 1.617021 (-1875 4300);
PAINT ORANGE (-1875 4300);
DISPLAY INVISIBLE (-1875 4300);
FORCEADD CAP..1
(-1425 3750);
FORCEPROP 1 LAST VOLTAGE 16V
J 0
(-1375 3750);
DISPLAY 0.617021 (-1375 3750);
PAINT SKYBLUE (-1375 3750);
FORCEPROP 1 LAST MATERIAL X7R
J 0
(-1375 3650);
DISPLAY 0.617021 (-1375 3650);
PAINT SKYBLUE (-1375 3650);
FORCEPROP 1 LAST PART_NUMBER A36096-155
J 0
(-1375 3600);
DISPLAY 0.617021 (-1375 3600);
PAINT BLUE (-1375 3600);
FORCEPROP 1 LAST VALUE 0.22UF
J 0
(-1375 3800);
DISPLAY 0.617021 (-1375 3800);
PAINT SKYBLUE (-1375 3800);
FORCEPROP 1 LAST LOCATION C4E23
J 0
(-1375 3850);
DISPLAY 0.617021 (-1375 3850);
PAINT AQUA (-1375 3850);
FORCEPROP 1 LASTPIN (-1425 3850) $PN 1
J 0
(-1415 3830);
DISPLAY 0.617021 (-1415 3830);
PAINT WHITE (-1415 3830);
FORCEPROP 1 LAST TOLERANCE 10%
J 0
(-1375 3700);
DISPLAY 0.617021 (-1375 3700);
PAINT SKYBLUE (-1375 3700);
FORCEPROP 1 LASTPIN (-1425 3650) $PN 2
J 0
(-1415 3630);
DISPLAY 0.617021 (-1415 3630);
PAINT WHITE (-1415 3630);
FORCEPROP 1 LAST PACK_TYPE 0402
J 0
(-1375 3550);
DISPLAY 0.617021 (-1375 3550);
PAINT SKYBLUE (-1375 3550);
FORCEPROP 2 LAST ROOM PVCCIO_CPU1
J 0
(-1375 3900);
DISPLAY 2.212766 (-1375 3900);
PAINT WHITE (-1375 3900);
DISPLAY INVISIBLE (-1375 3900);
FORCEPROP 1 LAST PATH I73
J 0
(-1375 3900);
DISPLAY 0.978723 (-1375 3900);
PAINT WHITE (-1375 3900);
DISPLAY INVISIBLE (-1375 3900);
FORCEPROP 2 LAST SEC_TYPE 0402
J 0
(-1375 3950);
DISPLAY 1.659574 (-1375 3950);
PAINT ORANGE (-1375 3950);
DISPLAY INVISIBLE (-1375 3950);
FORCEPROP 2 LAST SEC 1
J 0
(-1375 3950);
DISPLAY 1.106383 (-1375 3950);
PAINT MONO (-1375 3950);
DISPLAY INVISIBLE (-1375 3950);
FORCEPROP 2 LAST CDS_LOCATION C4E23
J 0
(-1375 3850);
DISPLAY 0.617021 (-1375 3850);
PAINT AQUA (-1375 3850);
DISPLAY INVISIBLE (-1375 3850);
FORCEPROP 2 LAST CDS_LIB mstr_discrete
J 0
(-1425 3750);
DISPLAY 1.617021 (-1425 3750);
PAINT ORANGE (-1425 3750);
DISPLAY INVISIBLE (-1425 3750);
FORCEADD CAP_A..1
R 2
(-1575 3775);
FORCEPROP 1 LAST PACK_TYPE 0402V
J 2
(-1625 3575);
DISPLAY 0.617021 (-1625 3575);
PAINT SKYBLUE (-1625 3575);
FORCEPROP 1 LAST PART_NUMBER D97712-004
J 2
(-1625 3625);
DISPLAY 0.617021 (-1625 3625);
PAINT BLUE (-1625 3625);
FORCEPROP 1 LAST VOLTAGE 6.3V
J 2
(-1625 3775);
DISPLAY 0.617021 (-1625 3775);
PAINT SKYBLUE (-1625 3775);
FORCEPROP 1 LAST LOCATION C4E28
J 2
(-1625 3875);
DISPLAY 0.617021 (-1625 3875);
PAINT AQUA (-1625 3875);
FORCEPROP 1 LASTPIN (-1575 3875) $PN 1
J 2
(-1585 3855);
DISPLAY 0.617021 (-1585 3855);
PAINT WHITE (-1585 3855);
FORCEPROP 1 LAST VALUE 1.0UF
J 2
(-1625 3825);
DISPLAY 0.617021 (-1625 3825);
PAINT SKYBLUE (-1625 3825);
FORCEPROP 1 LASTPIN (-1575 3675) $PN 2
J 2
(-1585 3655);
DISPLAY 0.617021 (-1585 3655);
PAINT WHITE (-1585 3655);
FORCEPROP 1 LAST MATERIAL X6S
J 2
(-1625 3675);
DISPLAY 0.617021 (-1625 3675);
PAINT SKYBLUE (-1625 3675);
FORCEPROP 1 LAST TOLERANCE 10%
J 2
(-1625 3725);
DISPLAY 0.617021 (-1625 3725);
PAINT SKYBLUE (-1625 3725);
FORCEPROP 2 LAST ROOM PVCCIO_CPU1
J 0
(-1625 3925);
DISPLAY 2.212766 (-1625 3925);
PAINT WHITE (-1625 3925);
DISPLAY INVISIBLE (-1625 3925);
FORCEPROP 1 LAST PATH I74
J 2
(-1625 3925);
DISPLAY 0.978723 (-1625 3925);
PAINT WHITE (-1625 3925);
DISPLAY INVISIBLE (-1625 3925);
FORCEPROP 2 LAST SEC 1
J 0
(-1625 3975);
DISPLAY 1.106383 (-1625 3975);
PAINT MONO (-1625 3975);
DISPLAY INVISIBLE (-1625 3975);
FORCEPROP 2 LAST CDS_SEC 1
J 0
(-1625 3925);
PAINT ORANGE (-1625 3925);
DISPLAY INVISIBLE (-1625 3925);
FORCEPROP 2 LAST SEC_TYPE 0402V
J 0
(-1625 3975);
DISPLAY 1.659574 (-1625 3975);
PAINT ORANGE (-1625 3975);
DISPLAY INVISIBLE (-1625 3975);
FORCEPROP 2 LAST CDS_LIB dev_discrete
J 0
(-1575 3775);
PAINT ORANGE (-1575 3775);
DISPLAY INVISIBLE (-1575 3775);
FORCEADD CAP..1
(-2125 3700);
FORCEPROP 1 LAST TOLERANCE 10%
J 0
(-2075 3650);
DISPLAY 0.617021 (-2075 3650);
PAINT SKYBLUE (-2075 3650);
FORCEPROP 1 LAST LOCATION C4E22
J 0
(-2075 3800);
DISPLAY 0.617021 (-2075 3800);
PAINT AQUA (-2075 3800);
FORCEPROP 1 LAST PART_NUMBER D97712-011
J 0
(-2075 3550);
DISPLAY 0.617021 (-2075 3550);
PAINT BLUE (-2075 3550);
FORCEPROP 1 LAST VALUE 1.0UF
J 0
(-2075 3750);
DISPLAY 0.617021 (-2075 3750);
PAINT SKYBLUE (-2075 3750);
FORCEPROP 1 LAST PACK_TYPE 0402
J 0
(-2075 3500);
DISPLAY 0.617021 (-2075 3500);
PAINT SKYBLUE (-2075 3500);
FORCEPROP 1 LAST VOLTAGE 16V
J 0
(-2075 3700);
DISPLAY 0.617021 (-2075 3700);
PAINT SKYBLUE (-2075 3700);
FORCEPROP 1 LAST MATERIAL X6S
J 0
(-2075 3600);
DISPLAY 0.617021 (-2075 3600);
PAINT SKYBLUE (-2075 3600);
FORCEPROP 1 LASTPIN (-2125 3800) $PN 1
J 0
(-2115 3780);
DISPLAY 0.617021 (-2115 3780);
PAINT WHITE (-2115 3780);
FORCEPROP 1 LASTPIN (-2125 3600) $PN 2
J 0
(-2115 3580);
DISPLAY 0.617021 (-2115 3580);
PAINT WHITE (-2115 3580);
FORCEPROP 2 LAST SEC_TYPE 0402
J 0
(-2075 3900);
DISPLAY 1.659574 (-2075 3900);
PAINT ORANGE (-2075 3900);
DISPLAY INVISIBLE (-2075 3900);
FORCEPROP 2 LAST SEC 1
J 0
(-2075 3900);
DISPLAY 1.106383 (-2075 3900);
PAINT MONO (-2075 3900);
DISPLAY INVISIBLE (-2075 3900);
FORCEPROP 1 LAST PATH I76
J 0
(-2075 3850);
DISPLAY 0.978723 (-2075 3850);
PAINT WHITE (-2075 3850);
DISPLAY INVISIBLE (-2075 3850);
FORCEPROP 2 LAST ROOM PVCCIO_CPU1
J 0
(-2075 3850);
DISPLAY 2.212766 (-2075 3850);
PAINT WHITE (-2075 3850);
DISPLAY INVISIBLE (-2075 3850);
FORCEPROP 2 LAST CDS_LIB mstr_discrete
J 0
(-2125 3700);
DISPLAY 1.617021 (-2125 3700);
PAINT ORANGE (-2125 3700);
DISPLAY INVISIBLE (-2125 3700);
FORCEPROP 2 LAST CDS_LOCATION C4E22
J 0
(-2075 3800);
DISPLAY 0.617021 (-2075 3800);
PAINT AQUA (-2075 3800);
DISPLAY INVISIBLE (-2075 3800);
FORCEADD CAP_A..1
(-2375 3725);
FORCEPROP 1 LAST PART_NUMBER A36096-030
J 0
(-2325 3575);
DISPLAY 0.617021 (-2325 3575);
PAINT BLUE (-2325 3575);
FORCEPROP 1 LAST LOCATION C4E13
J 0
(-2325 3825);
DISPLAY 0.617021 (-2325 3825);
PAINT AQUA (-2325 3825);
FORCEPROP 1 LAST VALUE 0.1UF
J 0
(-2325 3775);
DISPLAY 0.617021 (-2325 3775);
PAINT SKYBLUE (-2325 3775);
FORCEPROP 1 LAST TOLERANCE 10%
J 0
(-2325 3675);
DISPLAY 0.617021 (-2325 3675);
PAINT SKYBLUE (-2325 3675);
FORCEPROP 1 LAST VOLTAGE 16V
J 0
(-2325 3725);
DISPLAY 0.617021 (-2325 3725);
PAINT SKYBLUE (-2325 3725);
FORCEPROP 1 LAST MATERIAL X7R
J 0
(-2325 3625);
DISPLAY 0.617021 (-2325 3625);
PAINT SKYBLUE (-2325 3625);
FORCEPROP 1 LASTPIN (-2375 3825) $PN 1
J 0
(-2365 3805);
DISPLAY 0.617021 (-2365 3805);
PAINT WHITE (-2365 3805);
FORCEPROP 1 LASTPIN (-2375 3625) $PN 2
J 0
(-2365 3605);
DISPLAY 0.617021 (-2365 3605);
PAINT WHITE (-2365 3605);
FORCEPROP 1 LAST PACK_TYPE 0402V
J 0
(-2325 3525);
DISPLAY 0.617021 (-2325 3525);
PAINT SKYBLUE (-2325 3525);
FORCEPROP 2 LAST ROOM PVCCIO_CPU1
J 0
(-2325 3875);
DISPLAY 2.212766 (-2325 3875);
PAINT WHITE (-2325 3875);
DISPLAY INVISIBLE (-2325 3875);
FORCEPROP 2 LAST SEC 1
J 0
(-2325 3925);
DISPLAY 1.106383 (-2325 3925);
PAINT MONO (-2325 3925);
DISPLAY INVISIBLE (-2325 3925);
FORCEPROP 2 LAST SEC_TYPE 0402V
J 0
(-2325 3925);
DISPLAY 1.659574 (-2325 3925);
PAINT ORANGE (-2325 3925);
DISPLAY INVISIBLE (-2325 3925);
FORCEPROP 2 LAST CDS_SEC 1
J 0
(-2325 3875);
PAINT ORANGE (-2325 3875);
DISPLAY INVISIBLE (-2325 3875);
FORCEPROP 1 LAST PATH I77
J 0
(-2325 3875);
DISPLAY 0.978723 (-2325 3875);
PAINT WHITE (-2325 3875);
DISPLAY INVISIBLE (-2325 3875);
FORCEPROP 2 LAST CDS_LOCATION C4E13
J 0
(-2325 3825);
DISPLAY 0.617021 (-2325 3825);
PAINT AQUA (-2325 3825);
DISPLAY INVISIBLE (-2325 3825);
FORCEPROP 2 LAST CDS_LIB dev_discrete
J 0
(-2375 3725);
PAINT ORANGE (-2375 3725);
DISPLAY INVISIBLE (-2375 3725);
FORCEADD CAP..1
R 2
(-1675 3125);
FORCEPROP 1 LAST PART_NUMBER A36096-104
J 2
(-1725 2975);
DISPLAY 0.617021 (-1725 2975);
PAINT BLUE (-1725 2975);
FORCEPROP 1 LAST VOLTAGE 16V
J 2
(-1725 3125);
DISPLAY 0.617021 (-1725 3125);
PAINT SKYBLUE (-1725 3125);
FORCEPROP 1 LAST VALUE 0.220UF
J 2
(-1725 3175);
DISPLAY 0.617021 (-1725 3175);
PAINT SKYBLUE (-1725 3175);
FORCEPROP 1 LAST LOCATION C4E18
J 2
(-1725 3225);
DISPLAY 0.617021 (-1725 3225);
PAINT AQUA (-1725 3225);
FORCEPROP 1 LASTPIN (-1675 3225) $PN 1
J 2
(-1685 3205);
DISPLAY 0.617021 (-1685 3205);
PAINT ORANGE (-1685 3205);
FORCEPROP 1 LASTPIN (-1675 3025) $PN 2
J 2
(-1685 3005);
DISPLAY 0.617021 (-1685 3005);
PAINT ORANGE (-1685 3005);
FORCEPROP 1 LAST MATERIAL X7R
J 2
(-1725 3025);
DISPLAY 0.617021 (-1725 3025);
PAINT SKYBLUE (-1725 3025);
FORCEPROP 1 LAST PACK_TYPE 0402
J 2
(-1725 2925);
DISPLAY 0.617021 (-1725 2925);
PAINT SKYBLUE (-1725 2925);
FORCEPROP 1 LAST TOLERANCE 10%
J 2
(-1725 3075);
DISPLAY 0.617021 (-1725 3075);
PAINT SKYBLUE (-1725 3075);
FORCEPROP 2 LAST CDS_LOCATION C4E18
J 2
(-1725 3225);
DISPLAY 0.617021 (-1725 3225);
PAINT AQUA (-1725 3225);
DISPLAY INVISIBLE (-1725 3225);
FORCEPROP 2 LAST CDS_LIB mstr_discrete
J 0
(-1675 3125);
PAINT ORANGE (-1675 3125);
DISPLAY INVISIBLE (-1675 3125);
FORCEPROP 1 LAST PATH I78
J 2
(-1725 3275);
DISPLAY 0.978723 (-1725 3275);
PAINT WHITE (-1725 3275);
DISPLAY INVISIBLE (-1725 3275);
FORCEPROP 2 LAST SEC_TYPE 0402
J 0
(-1725 3325);
DISPLAY 1.021277 (-1725 3325);
PAINT ORANGE (-1725 3325);
DISPLAY INVISIBLE (-1725 3325);
FORCEPROP 2 LAST SEC 1
J 0
(-1725 3325);
DISPLAY 0.680851 (-1725 3325);
PAINT MONO (-1725 3325);
DISPLAY INVISIBLE (-1725 3325);
FORCEPROP 0 LAST SPOF TRUE
J 0
(-1725 3325);
DISPLAY 1.021277 (-1725 3325);
PAINT ORANGE (-1725 3325);
DISPLAY INVISIBLE (-1725 3325);
FORCEPROP 2 LAST ROOM PVCCIO_CPU1
J 0
(-1725 3275);
DISPLAY 2.212766 (-1725 3275);
PAINT WHITE (-1725 3275);
DISPLAY INVISIBLE (-1725 3275);
FORCEADD CAP..1
(-2600 3700);
FORCEPROP 1 LAST LOCATION C4E15
J 0
(-2550 3800);
DISPLAY 0.617021 (-2550 3800);
PAINT AQUA (-2550 3800);
FORCEPROP 1 LAST VALUE 1.0UF
J 0
(-2550 3750);
DISPLAY 0.617021 (-2550 3750);
PAINT SKYBLUE (-2550 3750);
FORCEPROP 1 LAST TOLERANCE 10%
J 0
(-2550 3650);
DISPLAY 0.617021 (-2550 3650);
PAINT SKYBLUE (-2550 3650);
FORCEPROP 1 LAST VOLTAGE 16V
J 0
(-2550 3700);
DISPLAY 0.617021 (-2550 3700);
PAINT SKYBLUE (-2550 3700);
FORCEPROP 1 LAST MATERIAL X6S
J 0
(-2550 3600);
DISPLAY 0.617021 (-2550 3600);
PAINT SKYBLUE (-2550 3600);
FORCEPROP 1 LAST PART_NUMBER D97712-011
J 0
(-2550 3550);
DISPLAY 0.617021 (-2550 3550);
PAINT BLUE (-2550 3550);
FORCEPROP 1 LAST PACK_TYPE 0402
J 0
(-2550 3500);
DISPLAY 0.617021 (-2550 3500);
PAINT SKYBLUE (-2550 3500);
FORCEPROP 1 LASTPIN (-2600 3800) $PN 1
J 0
(-2590 3780);
DISPLAY 0.617021 (-2590 3780);
PAINT WHITE (-2590 3780);
FORCEPROP 1 LASTPIN (-2600 3600) $PN 2
J 0
(-2590 3580);
DISPLAY 0.617021 (-2590 3580);
PAINT WHITE (-2590 3580);
FORCEPROP 2 LAST ROOM PVCCIO_CPU1
J 0
(-2550 3850);
DISPLAY 2.212766 (-2550 3850);
PAINT WHITE (-2550 3850);
DISPLAY INVISIBLE (-2550 3850);
FORCEPROP 2 LAST SEC_TYPE 0402
J 0
(-2550 3900);
DISPLAY 1.659574 (-2550 3900);
PAINT ORANGE (-2550 3900);
DISPLAY INVISIBLE (-2550 3900);
FORCEPROP 2 LAST SEC 1
J 0
(-2550 3900);
DISPLAY 1.106383 (-2550 3900);
PAINT MONO (-2550 3900);
DISPLAY INVISIBLE (-2550 3900);
FORCEPROP 1 LAST PATH I79
J 0
(-2550 3850);
DISPLAY 0.978723 (-2550 3850);
PAINT WHITE (-2550 3850);
DISPLAY INVISIBLE (-2550 3850);
FORCEPROP 2 LAST CDS_LOCATION C4E15
J 0
(-2550 3800);
DISPLAY 0.617021 (-2550 3800);
PAINT AQUA (-2550 3800);
DISPLAY INVISIBLE (-2550 3800);
FORCEPROP 2 LAST CDS_LIB mstr_discrete
J 0
(-2600 3700);
DISPLAY 1.617021 (-2600 3700);
PAINT ORANGE (-2600 3700);
DISPLAY INVISIBLE (-2600 3700);
FORCEADD CAP..1
R 2
(1650 1900);
FORCEPROP 1 LAST MATERIAL X5R
J 2
(1600 1800);
DISPLAY 0.617021 (1600 1800);
PAINT SKYBLUE (1600 1800);
FORCEPROP 1 LAST VOLTAGE 16V
J 2
(1600 1900);
DISPLAY 0.617021 (1600 1900);
PAINT SKYBLUE (1600 1900);
FORCEPROP 1 LAST PACK_TYPE 1210
J 2
(1625 1750);
DISPLAY 0.617021 (1625 1750);
PAINT SKYBLUE (1625 1750);
FORCEPROP 1 LAST TOLERANCE 20%
J 2
(1600 1850);
DISPLAY 0.617021 (1600 1850);
PAINT SKYBLUE (1600 1850);
FORCEPROP 1 LAST VALUE 100UF
J 2
(1600 1950);
DISPLAY 0.617021 (1600 1950);
PAINT SKYBLUE (1600 1950);
FORCEPROP 1 LAST LOCATION C4E9
J 2
(1600 2000);
DISPLAY 0.617021 (1600 2000);
PAINT AQUA (1600 2000);
FORCEPROP 1 LASTPIN (1650 1800) $PN 2
J 2
(1640 1780);
DISPLAY 0.617021 (1640 1780);
PAINT WHITE (1640 1780);
FORCEPROP 1 LASTPIN (1650 2000) $PN 1
J 2
(1640 1980);
DISPLAY 0.617021 (1640 1980);
PAINT WHITE (1640 1980);
FORCEPROP 1 LAST PART_NUMBER 644066-127
J 2
(1629 1704);
DISPLAY 0.617021 (1629 1704);
PAINT BLUE (1629 1704);
FORCEPROP 2 LAST CDS_LIB mstr_discrete
J 0
(1650 1900);
PAINT ORANGE (1650 1900);
DISPLAY INVISIBLE (1650 1900);
FORCEPROP 2 LAST BOM_COST PROC_VRD_PVCCIO_CPU1
J 0
(1600 2050);
DISPLAY 0.723404 (1600 2050);
PAINT ORANGE (1600 2050);
DISPLAY INVISIBLE (1600 2050);
FORCEPROP 2 LAST CDS_LOCATION C4E9
J 2
(1600 2000);
DISPLAY 0.617021 (1600 2000);
PAINT AQUA (1600 2000);
DISPLAY INVISIBLE (1600 2000);
FORCEPROP 1 LAST PATH I8
J 2
(1600 2050);
DISPLAY 0.978723 (1600 2050);
PAINT WHITE (1600 2050);
DISPLAY INVISIBLE (1600 2050);
FORCEPROP 2 LAST ROOM PVCCIO_CPU1
J 0
(1600 2050);
DISPLAY 0.723404 (1600 2050);
PAINT ORANGE (1600 2050);
DISPLAY INVISIBLE (1600 2050);
FORCEPROP 2 LAST $SEC 1
J 0
(1617 2112);
PAINT MONO (1617 2112);
DISPLAY INVISIBLE (1617 2112);
FORCEPROP 2 LAST CDS_SEC 1
J 0
(1617 2112);
PAINT MONO (1617 2112);
DISPLAY INVISIBLE (1617 2112);
FORCEADD CAP..1
(-2825 3725);
FORCEPROP 1 LAST PART_NUMBER C95333-007
J 0
(-2775 3575);
DISPLAY 0.617021 (-2775 3575);
PAINT BLUE (-2775 3575);
FORCEPROP 1 LAST LOCATION C6R14
J 0
(-2775 3825);
DISPLAY 0.617021 (-2775 3825);
PAINT AQUA (-2775 3825);
FORCEPROP 1 LAST VALUE 10UF
J 0
(-2775 3775);
DISPLAY 0.617021 (-2775 3775);
PAINT SKYBLUE (-2775 3775);
FORCEPROP 1 LAST TOLERANCE 10%
J 0
(-2775 3675);
DISPLAY 0.617021 (-2775 3675);
PAINT SKYBLUE (-2775 3675);
FORCEPROP 1 LAST VOLTAGE 16V
J 0
(-2775 3725);
DISPLAY 0.617021 (-2775 3725);
PAINT SKYBLUE (-2775 3725);
FORCEPROP 1 LAST MATERIAL X6S
J 0
(-2775 3625);
DISPLAY 0.617021 (-2775 3625);
PAINT SKYBLUE (-2775 3625);
FORCEPROP 1 LASTPIN (-2825 3825) $PN 1
J 0
(-2815 3805);
DISPLAY 0.617021 (-2815 3805);
PAINT WHITE (-2815 3805);
FORCEPROP 1 LASTPIN (-2825 3625) $PN 2
J 0
(-2815 3605);
DISPLAY 0.617021 (-2815 3605);
PAINT WHITE (-2815 3605);
FORCEPROP 1 LAST PACK_TYPE 0805
J 0
(-2775 3525);
DISPLAY 0.617021 (-2775 3525);
PAINT SKYBLUE (-2775 3525);
FORCEPROP 2 LAST ROOM PVCCIO_CPU1
J 0
(-2775 3875);
DISPLAY 2.212766 (-2775 3875);
PAINT WHITE (-2775 3875);
DISPLAY INVISIBLE (-2775 3875);
FORCEPROP 1 LAST PATH I80
J 0
(-2775 3875);
DISPLAY 0.978723 (-2775 3875);
PAINT WHITE (-2775 3875);
DISPLAY INVISIBLE (-2775 3875);
FORCEPROP 2 LAST SEC_TYPE 0805
J 0
(-2775 3925);
DISPLAY 1.659574 (-2775 3925);
PAINT ORANGE (-2775 3925);
DISPLAY INVISIBLE (-2775 3925);
FORCEPROP 2 LAST SEC 1
J 0
(-2775 3925);
DISPLAY 1.106383 (-2775 3925);
PAINT MONO (-2775 3925);
DISPLAY INVISIBLE (-2775 3925);
FORCEPROP 2 LAST CDS_LOCATION C6R14
J 0
(-2775 3825);
DISPLAY 0.617021 (-2775 3825);
PAINT AQUA (-2775 3825);
DISPLAY INVISIBLE (-2775 3825);
FORCEPROP 2 LAST CDS_LIB mstr_discrete
J 0
(-2825 3725);
DISPLAY 1.617021 (-2825 3725);
PAINT ORANGE (-2825 3725);
DISPLAY INVISIBLE (-2825 3725);
FORCEADD CAP..1
(-3050 3700);
FORCEPROP 1 LAST TOLERANCE 10%
J 0
(-3000 3650);
DISPLAY 0.617021 (-3000 3650);
PAINT SKYBLUE (-3000 3650);
FORCEPROP 1 LAST VOLTAGE 16V
J 0
(-3000 3700);
DISPLAY 0.617021 (-3000 3700);
PAINT SKYBLUE (-3000 3700);
FORCEPROP 1 LAST MATERIAL X6S
J 0
(-3000 3600);
DISPLAY 0.617021 (-3000 3600);
PAINT SKYBLUE (-3000 3600);
FORCEPROP 1 LAST VALUE 10UF
J 0
(-3000 3750);
DISPLAY 0.617021 (-3000 3750);
PAINT SKYBLUE (-3000 3750);
FORCEPROP 1 LAST LOCATION C6R10
J 0
(-3000 3800);
DISPLAY 0.617021 (-3000 3800);
PAINT AQUA (-3000 3800);
FORCEPROP 1 LASTPIN (-3050 3800) $PN 1
J 0
(-3040 3780);
DISPLAY 0.617021 (-3040 3780);
PAINT WHITE (-3040 3780);
FORCEPROP 1 LASTPIN (-3050 3600) $PN 2
J 0
(-3040 3580);
DISPLAY 0.617021 (-3040 3580);
PAINT WHITE (-3040 3580);
FORCEPROP 1 LAST PART_NUMBER C95333-007
J 0
(-3000 3550);
DISPLAY 0.617021 (-3000 3550);
PAINT BLUE (-3000 3550);
FORCEPROP 1 LAST PACK_TYPE 0805
J 0
(-3000 3500);
DISPLAY 0.617021 (-3000 3500);
PAINT SKYBLUE (-3000 3500);
FORCEPROP 2 LAST SEC_TYPE 0805
J 0
(-3000 3900);
DISPLAY 1.659574 (-3000 3900);
PAINT ORANGE (-3000 3900);
DISPLAY INVISIBLE (-3000 3900);
FORCEPROP 2 LAST SEC 1
J 0
(-3000 3900);
DISPLAY 1.106383 (-3000 3900);
PAINT MONO (-3000 3900);
DISPLAY INVISIBLE (-3000 3900);
FORCEPROP 1 LAST PATH I81
J 0
(-3000 3850);
DISPLAY 0.978723 (-3000 3850);
PAINT WHITE (-3000 3850);
DISPLAY INVISIBLE (-3000 3850);
FORCEPROP 2 LAST ROOM PVCCIO_CPU1
J 0
(-3000 3850);
DISPLAY 2.212766 (-3000 3850);
PAINT WHITE (-3000 3850);
DISPLAY INVISIBLE (-3000 3850);
FORCEPROP 2 LAST CDS_LOCATION C6R10
J 0
(-3000 3800);
DISPLAY 0.617021 (-3000 3800);
PAINT AQUA (-3000 3800);
DISPLAY INVISIBLE (-3000 3800);
FORCEPROP 2 LAST CDS_LIB mstr_discrete
J 0
(-3050 3700);
DISPLAY 1.617021 (-3050 3700);
PAINT ORANGE (-3050 3700);
DISPLAY INVISIBLE (-3050 3700);
FORCEADD OFFPAGE..1
(-2550 3375);
FORCEPROP 2 LAST $XR0 213 
J 0
(-2802 3375);
DISPLAY 0.638298 (-2802 3375);
PAINT MONO (-2802 3375);
FORCEPROP 1 LAST OFFPAGE TRUE
J 0
(-2225 3250);
PAINT GREEN (-2225 3250);
DISPLAY INVISIBLE (-2225 3250);
FORCEPROP 2 LAST CDS_LIB mstr_standard
J 0
(-2550 3375);
DISPLAY 1.617021 (-2550 3375);
PAINT ORANGE (-2550 3375);
DISPLAY INVISIBLE (-2550 3375);
FORCEPROP 1 LAST COMMENT_BODY TRUE
J 0
(-2425 3275);
DISPLAY 2.723404 (-2425 3275);
PAINT PEACH (-2425 3275);
DISPLAY INVISIBLE (-2425 3275);
FORCEPROP 2 LAST PATH I82
J 0
(-2500 3450);
DISPLAY 1.021277 (-2500 3450);
PAINT ORANGE (-2500 3450);
DISPLAY INVISIBLE (-2500 3450);
FORCEPROP 2 LAST BOM_COST PROC_VRD_PVCCIO_CPU1
J 0
(-2800 3425);
DISPLAY 2.340426 (-2800 3425);
PAINT WHITE (-2800 3425);
DISPLAY INVISIBLE (-2800 3425);
FORCEPROP 2 LAST ROOM PVCCIO_CPU1
J 0
(-2950 3450);
DISPLAY 3.127660 (-2950 3450);
PAINT WHITE (-2950 3450);
DISPLAY INVISIBLE (-2950 3450);
FORCEADD CAP..1
(-3275 3725);
FORCEPROP 1 LAST PART_NUMBER C95333-007
J 0
(-3225 3575);
DISPLAY 0.617021 (-3225 3575);
PAINT BLUE (-3225 3575);
FORCEPROP 1 LAST LOCATION C6R8
J 0
(-3225 3825);
DISPLAY 0.617021 (-3225 3825);
PAINT AQUA (-3225 3825);
FORCEPROP 1 LAST VALUE 10UF
J 0
(-3225 3775);
DISPLAY 0.617021 (-3225 3775);
PAINT SKYBLUE (-3225 3775);
FORCEPROP 1 LAST TOLERANCE 10%
J 0
(-3225 3675);
DISPLAY 0.617021 (-3225 3675);
PAINT SKYBLUE (-3225 3675);
FORCEPROP 1 LAST VOLTAGE 16V
J 0
(-3225 3725);
DISPLAY 0.617021 (-3225 3725);
PAINT SKYBLUE (-3225 3725);
FORCEPROP 1 LAST MATERIAL X6S
J 0
(-3225 3625);
DISPLAY 0.617021 (-3225 3625);
PAINT SKYBLUE (-3225 3625);
FORCEPROP 1 LASTPIN (-3275 3825) $PN 1
J 0
(-3265 3805);
DISPLAY 0.617021 (-3265 3805);
PAINT WHITE (-3265 3805);
FORCEPROP 1 LASTPIN (-3275 3625) $PN 2
J 0
(-3265 3605);
DISPLAY 0.617021 (-3265 3605);
PAINT WHITE (-3265 3605);
FORCEPROP 1 LAST PACK_TYPE 0805
J 0
(-3225 3525);
DISPLAY 0.617021 (-3225 3525);
PAINT SKYBLUE (-3225 3525);
FORCEPROP 2 LAST ROOM PVCCIO_CPU1
J 0
(-3225 3875);
DISPLAY 2.212766 (-3225 3875);
PAINT WHITE (-3225 3875);
DISPLAY INVISIBLE (-3225 3875);
FORCEPROP 1 LAST PATH I83
J 0
(-3225 3875);
DISPLAY 0.978723 (-3225 3875);
PAINT WHITE (-3225 3875);
DISPLAY INVISIBLE (-3225 3875);
FORCEPROP 2 LAST SEC 1
J 0
(-3225 3925);
DISPLAY 1.106383 (-3225 3925);
PAINT MONO (-3225 3925);
DISPLAY INVISIBLE (-3225 3925);
FORCEPROP 2 LAST SEC_TYPE 0805
J 0
(-3225 3925);
DISPLAY 1.659574 (-3225 3925);
PAINT ORANGE (-3225 3925);
DISPLAY INVISIBLE (-3225 3925);
FORCEPROP 2 LAST CDS_LOCATION C6R8
J 0
(-3225 3825);
DISPLAY 0.617021 (-3225 3825);
PAINT AQUA (-3225 3825);
DISPLAY INVISIBLE (-3225 3825);
FORCEPROP 2 LAST CDS_LIB mstr_discrete
J 0
(-3275 3725);
DISPLAY 1.617021 (-3275 3725);
PAINT ORANGE (-3275 3725);
DISPLAY INVISIBLE (-3275 3725);
FORCEADD GND..1
(-3275 3375);
FORCEPROP 3 LASTPIN (-3275 3425) SIG_NAME GND\g
J 0
(-3265 3435);
DISPLAY 0.659574 (-3265 3435);
PAINT MONO (-3265 3435);
DISPLAY INVISIBLE (-3265 3435);
FORCEPROP 1 LAST HDL_POWER GND
J 0
(-3275 3525);
DISPLAY 2.787234 (-3275 3525);
PAINT GREEN (-3275 3525);
DISPLAY INVISIBLE (-3275 3525);
FORCEPROP 1 LAST PATH I84
J 0
(-3200 3375);
DISPLAY 0.872340 (-3200 3375);
PAINT AQUA (-3200 3375);
DISPLAY INVISIBLE (-3200 3375);
FORCEPROP 1 LAST VOLTAGE 0.0V
J 0
(-3320 3332);
DISPLAY 0.340426 (-3320 3332);
PAINT SKYBLUE (-3320 3332);
DISPLAY INVISIBLE (-3320 3332);
FORCEPROP 1 LAST BODY_TYPE PLUMBING
J 0
(-3320 3332);
DISPLAY 0.340426 (-3320 3332);
PAINT GREEN (-3320 3332);
DISPLAY INVISIBLE (-3320 3332);
FORCEPROP 2 LAST CDS_LIB mstr_symbols
J 0
(-3275 3375);
DISPLAY 1.617021 (-3275 3375);
PAINT ORANGE (-3275 3375);
DISPLAY INVISIBLE (-3275 3375);
FORCEPROP 1 LAST SIZE 1B
J 0
(-3200 3325);
DISPLAY 2.787234 (-3200 3325);
PAINT GREEN (-3200 3325);
DISPLAY INVISIBLE (-3200 3325);
FORCEPROP 2 LAST ROOM PVCCIO_CPU1
J 0
(-3825 3450);
DISPLAY 3.127660 (-3825 3450);
PAINT WHITE (-3825 3450);
DISPLAY INVISIBLE (-3825 3450);
FORCEPROP 2 LAST BOM_COST PROC_VRD_PVCCIO_CPU1
J 0
(-3650 3450);
DISPLAY 2.340426 (-3650 3450);
PAINT WHITE (-3650 3450);
DISPLAY INVISIBLE (-3650 3450);
FORCEADD P5V_STBY..1
(-900 4400);
FORCEPROP 3 LASTPIN (-900 4350) SIG_NAME P5V_STBY\g
J 0
(-890 4360);
DISPLAY 0.659574 (-890 4360);
PAINT MONO (-890 4360);
DISPLAY INVISIBLE (-890 4360);
FORCEPROP 2 LAST CDS_LIB mstr_symbols
J 0
(-900 4400);
PAINT ORANGE (-900 4400);
DISPLAY INVISIBLE (-900 4400);
FORCEPROP 1 LAST SIZE 1B
J 0
(-855 4422);
DISPLAY 0.340426 (-855 4422);
PAINT GREEN (-855 4422);
DISPLAY INVISIBLE (-855 4422);
FORCEPROP 1 LAST BODY_TYPE PLUMBING
J 0
(-945 4357);
DISPLAY 0.340426 (-945 4357);
PAINT GREEN (-945 4357);
DISPLAY INVISIBLE (-945 4357);
FORCEPROP 1 LAST PATH I88
J 0
(-855 4402);
DISPLAY 0.340426 (-855 4402);
PAINT GREEN (-855 4402);
DISPLAY INVISIBLE (-855 4402);
FORCEPROP 1 LAST VOLTAGE 5.0V
J 0
(-945 4357);
DISPLAY 0.340426 (-945 4357);
PAINT SKYBLUE (-945 4357);
DISPLAY INVISIBLE (-945 4357);
FORCEPROP 1 LAST HDL_POWER P5V_STBY
J 0
(-1200 4275);
DISPLAY 0.872340 (-1200 4275);
PAINT ORANGE (-1200 4275);
DISPLAY INVISIBLE (-1200 4275);
FORCEADD UNIVERSAL_POWER..1
(-3275 4250);
FORCEPROP 3 LASTPIN (-3275 4200) SIG_NAME VR_FET_SW_P12V_STBY_PVCCIN_CPU0\g
J 0
(-3265 4210);
DISPLAY 0.659574 (-3265 4210);
PAINT MONO (-3265 4210);
DISPLAY INVISIBLE (-3265 4210);
FORCEPROP 1 LAST HDL_POWER VR_FET_SW_P12V_STBY_PVCCIN_CPU0
J 1
(-3175 4300);
DISPLAY 0.617021 (-3175 4300);
PAINT GREEN (-3175 4300);
FORCEPROP 1 LAST PATH I89
J 0
(-3225 4275);
DISPLAY 0.872340 (-3225 4275);
PAINT AQUA (-3225 4275);
DISPLAY INVISIBLE (-3225 4275);
FORCEPROP 2 LAST CDS_LIB mstr_symbols
J 0
(-3275 4250);
PAINT ORANGE (-3275 4250);
DISPLAY INVISIBLE (-3275 4250);
FORCEADD GND..1
(1650 1625);
FORCEPROP 3 LASTPIN (1650 1675) SIG_NAME GND\g
J 0
(1660 1685);
DISPLAY 0.659574 (1660 1685);
PAINT MONO (1660 1685);
DISPLAY INVISIBLE (1660 1685);
FORCEPROP 1 LAST SIZE 1B
J 0
(1725 1575);
DISPLAY 0.553191 (1725 1575);
PAINT ORANGE (1725 1575);
DISPLAY INVISIBLE (1725 1575);
FORCEPROP 1 LAST BODY_TYPE PLUMBING
J 0
(1605 1582);
DISPLAY 0.340426 (1605 1582);
PAINT GREEN (1605 1582);
DISPLAY INVISIBLE (1605 1582);
FORCEPROP 2 LAST CDS_LIB mstr_symbols
J 0
(1650 1625);
PAINT ORANGE (1650 1625);
DISPLAY INVISIBLE (1650 1625);
FORCEPROP 1 LAST PATH I9
J 0
(1725 1625);
DISPLAY 0.872340 (1725 1625);
PAINT AQUA (1725 1625);
DISPLAY INVISIBLE (1725 1625);
FORCEPROP 1 LAST VOLTAGE 0.0V
J 0
(1605 1582);
DISPLAY 0.340426 (1605 1582);
PAINT SKYBLUE (1605 1582);
DISPLAY INVISIBLE (1605 1582);
FORCEPROP 2 LAST BOM_COST PROC_VRD_PVCCIO_CPU1
J 0
(1300 1700);
DISPLAY 0.617021 (1300 1700);
PAINT ORANGE (1300 1700);
DISPLAY INVISIBLE (1300 1700);
FORCEPROP 2 LAST ROOM PVCCIO_CPU1
J 0
(1350 1700);
DISPLAY 0.723404 (1350 1700);
PAINT ORANGE (1350 1700);
DISPLAY INVISIBLE (1350 1700);
FORCEPROP 1 LAST HDL_POWER GND
J 0
(1650 1775);
DISPLAY 0.553191 (1650 1775);
PAINT GREEN (1650 1775);
DISPLAY INVISIBLE (1650 1775);
FORCEADD OFFPAGE..1
(-3050 1300);
FORCEPROP 2 LAST $XR0 73 
J 0
(-3301 1300);
DISPLAY 0.638298 (-3301 1300);
PAINT MONO (-3301 1300);
FORCEPROP 1 LAST COMMENT_BODY TRUE
J 0
(-2925 1200);
DISPLAY 0.893617 (-2925 1200);
PAINT GREEN (-2925 1200);
DISPLAY INVISIBLE (-2925 1200);
FORCEPROP 1 LAST OFFPAGE TRUE
J 0
(-2725 1175);
DISPLAY 0.893617 (-2725 1175);
PAINT GREEN (-2725 1175);
DISPLAY INVISIBLE (-2725 1175);
FORCEPROP 2 LAST CDS_LIB mstr_standard
J 0
(-3050 1300);
PAINT ORANGE (-3050 1300);
DISPLAY INVISIBLE (-3050 1300);
FORCEPROP 2 LAST PATH I95
J 0
(-3300 1350);
DISPLAY 1.021277 (-3300 1350);
PAINT ORANGE (-3300 1350);
DISPLAY INVISIBLE (-3300 1350);
FORCEPROP 2 LAST ROOM VCCIN_CPU0_DECAP_VR
J 0
(-3575 1375);
PAINT ORANGE (-3575 1375);
DISPLAY INVISIBLE (-3575 1375);
FORCEPROP 2 LAST BOM_COST PROC_VRD_VCCIN_CPU0
J 0
(-3250 1350);
PAINT MONO (-3250 1350);
DISPLAY INVISIBLE (-3250 1350);
FORCEADD CAP_A..1
(-1725 1575);
FORCEPROP 1 LAST MATERIAL EMPTY
J 0
(-1675 1475);
DISPLAY 0.617021 (-1675 1475);
PAINT RED (-1675 1475);
FORCEPROP 1 LAST LOCATION C3D27
J 0
(-1675 1675);
DISPLAY 0.617021 (-1675 1675);
PAINT AQUA (-1675 1675);
FORCEPROP 1 LAST PART_NUMBER A36096-030
J 0
(-1675 1425);
DISPLAY 0.617021 (-1675 1425);
PAINT BLUE (-1675 1425);
FORCEPROP 1 LAST VALUE 0.1UF
J 0
(-1675 1625);
DISPLAY 0.617021 (-1675 1625);
PAINT SKYBLUE (-1675 1625);
FORCEPROP 1 LAST PACK_TYPE 0402V
J 0
(-1675 1375);
DISPLAY 0.617021 (-1675 1375);
PAINT SKYBLUE (-1675 1375);
FORCEPROP 1 LAST VOLTAGE 16V
J 0
(-1675 1575);
DISPLAY 0.617021 (-1675 1575);
PAINT SKYBLUE (-1675 1575);
FORCEPROP 1 LASTPIN (-1725 1675) $PN 1
J 0
(-1715 1655);
DISPLAY 0.617021 (-1715 1655);
PAINT ORANGE (-1715 1655);
FORCEPROP 1 LAST TOLERANCE 10%
J 0
(-1675 1525);
DISPLAY 0.617021 (-1675 1525);
PAINT SKYBLUE (-1675 1525);
FORCEPROP 1 LASTPIN (-1725 1475) $PN 2
J 0
(-1715 1455);
DISPLAY 0.617021 (-1715 1455);
PAINT ORANGE (-1715 1455);
FORCEPROP 2 LAST SEC_TYPE 0402V
J 0
(-1675 1775);
DISPLAY 1.021277 (-1675 1775);
PAINT ORANGE (-1675 1775);
DISPLAY INVISIBLE (-1675 1775);
FORCEPROP 2 LAST SEC 1
J 0
(-1675 1775);
DISPLAY 0.680851 (-1675 1775);
PAINT MONO (-1675 1775);
DISPLAY INVISIBLE (-1675 1775);
FORCEPROP 2 LAST ROOM PVCCIO_CPU1
J 0
(-1675 1725);
DISPLAY 0.723404 (-1675 1725);
PAINT ORANGE (-1675 1725);
DISPLAY INVISIBLE (-1675 1725);
FORCEPROP 1 LAST PATH I96
J 0
(-1675 1725);
DISPLAY 0.978723 (-1675 1725);
PAINT WHITE (-1675 1725);
DISPLAY INVISIBLE (-1675 1725);
FORCEPROP 2 LAST CDS_LOCATION C3D27
J 0
(-1675 1675);
DISPLAY 0.617021 (-1675 1675);
PAINT AQUA (-1675 1675);
DISPLAY INVISIBLE (-1675 1675);
FORCEPROP 2 LAST BOM_COST PROC_VRD_VCCIO_CPU1
J 0
(-1675 1725);
DISPLAY 0.723404 (-1675 1725);
PAINT ORANGE (-1675 1725);
DISPLAY INVISIBLE (-1675 1725);
FORCEPROP 2 LAST CDS_LIB dev_discrete
J 0
(-1725 1575);
PAINT ORANGE (-1725 1575);
DISPLAY INVISIBLE (-1725 1575);
FORCEADD OFFPAGE..1
(-3050 1750);
FORCEPROP 2 LAST $XR0 73 
J 0
(-3301 1750);
DISPLAY 0.638298 (-3301 1750);
PAINT MONO (-3301 1750);
FORCEPROP 1 LAST COMMENT_BODY TRUE
J 0
(-2925 1650);
DISPLAY 0.893617 (-2925 1650);
PAINT GREEN (-2925 1650);
DISPLAY INVISIBLE (-2925 1650);
FORCEPROP 1 LAST OFFPAGE TRUE
J 0
(-2725 1625);
DISPLAY 0.893617 (-2725 1625);
PAINT GREEN (-2725 1625);
DISPLAY INVISIBLE (-2725 1625);
FORCEPROP 2 LAST CDS_LIB mstr_standard
J 2
(-3050 1750);
PAINT ORANGE (-3050 1750);
DISPLAY INVISIBLE (-3050 1750);
FORCEPROP 2 LAST BOM_COST PROC_VRD_VCCIN_CPU0
J 0
(-3250 1800);
PAINT MONO (-3250 1800);
DISPLAY INVISIBLE (-3250 1800);
FORCEPROP 2 LAST PATH I97
J 0
(-3300 1800);
DISPLAY 1.021277 (-3300 1800);
PAINT ORANGE (-3300 1800);
DISPLAY INVISIBLE (-3300 1800);
FORCEPROP 2 LAST ROOM VCCIN_CPU0_DECAP_VR
J 0
(-3575 1825);
PAINT ORANGE (-3575 1825);
DISPLAY INVISIBLE (-3575 1825);
FORCEADD DESIGN_NOTE..1
(-3300 2625);
PAINT PURPLE (-3300 2625);
FORCEPROP 2 LAST ROOM PVCCIN_CPU0_VR
J 0
(-3500 2575);
PAINT MONO (-3500 2575);
DISPLAY INVISIBLE (-3500 2575);
FORCEPROP 1 LAST COMMENT_BODY TRUE
J 0
(-3275 2725);
DISPLAY 1.319149 (-3275 2725);
PAINT GREEN (-3275 2725);
DISPLAY INVISIBLE (-3275 2725);
FORCEPROP 2 LAST CDS_LIB mstr_symbols
J 0
(-3300 2625);
PAINT ORANGE (-3300 2625);
DISPLAY INVISIBLE (-3300 2625);
FORCEPROP 2 LAST BOM_COST SM_CONTROLLER
J 0
(-3500 2575);
PAINT MONO (-3500 2575);
DISPLAY INVISIBLE (-3500 2575);
FORCEADD DNS..3
(-1120 1745);
PAINT RED (-1120 1745);
FORCEPROP 2 LAST CDS_LIB mstr_misc
J 0
(-1120 1745);
PAINT ORANGE (-1120 1745);
DISPLAY INVISIBLE (-1120 1745);
FORCEPROP 1 LAST COMMENT_BODY TRUE
R 1
J 0
(-1045 1520);
DISPLAY 0.872340 (-1045 1520);
PAINT GREEN (-1045 1520);
DISPLAY INVISIBLE (-1045 1520);
FORCEADD DNS..2
(-1720 1570);
PAINT RED (-1720 1570);
FORCEPROP 2 LAST CDS_LIB mstr_misc
J 0
(-1720 1570);
PAINT ORANGE (-1720 1570);
DISPLAY INVISIBLE (-1720 1570);
FORCEPROP 1 LAST COMMENT_BODY TRUE
R 1
J 0
(-1645 1345);
DISPLAY 0.872340 (-1645 1345);
PAINT GREEN (-1645 1345);
DISPLAY INVISIBLE (-1645 1345);
FORCEADD DNS..3
(-1120 1295);
PAINT RED (-1120 1295);
FORCEPROP 2 LAST CDS_LIB mstr_misc
J 0
(-1120 1295);
PAINT ORANGE (-1120 1295);
DISPLAY INVISIBLE (-1120 1295);
FORCEPROP 1 LAST COMMENT_BODY TRUE
R 1
J 0
(-1045 1070);
DISPLAY 0.872340 (-1045 1070);
PAINT GREEN (-1045 1070);
DISPLAY INVISIBLE (-1045 1070);
FORCEADD DNS..2
(3180 3620);
PAINT RED (3180 3620);
FORCEPROP 2 LAST CDS_LIB mstr_misc
J 0
(3180 3620);
PAINT ORANGE (3180 3620);
DISPLAY INVISIBLE (3180 3620);
FORCEPROP 1 LAST COMMENT_BODY TRUE
R 1
J 0
(3255 3395);
DISPLAY 0.872340 (3255 3395);
PAINT GREEN (3255 3395);
DISPLAY INVISIBLE (3255 3395);
FORCEADD INTEL_CORP_BPAGE..1
(4250 200);
FORCEPROP 1 LAST CDS_CON_LAST_MODIFIED Tue Dec 01 11:52:24 2015
J 0
(2825 525);
PAINT ORANGE (2825 525);
DISPLAY INVISIBLE (2825 525);
FORCEPROP 1 LAST CUSTOM_TXT_CDS <CURRENT_DESIGN_SHEET> OF <TOTAL_DESIGN_SHEETS>
J 0
(3750 225);
PAINT GREEN (3750 225);
FORCEPROP 1 LAST CUSTOM_TXT_CDS <CON_LAST_MODIFIED>
J 0
(2325 550);
PAINT GREEN (2325 550);
FORCEPROP 2 LAST CUSTOM_TXT_CDS <XR_PAGE_TITLE>
J 0
(-3640 5450);
DISPLAY 0.638298 (-3640 5450);
PAINT PINK (-3640 5450);
DISPLAY INVISIBLE (-3640 5450);
FORCEPROP 1 LAST SCH_NUMBER H4694802
J 0
(2950 350);
DISPLAY 1.212766 (2950 350);
PAINT YELLOW (2950 350);
FORCEPROP 1 LAST SCH_DEPT BESD
J 1
(-200 300);
DISPLAY 1.212766 (-200 300);
PAINT YELLOW (-200 300);
FORCEPROP 1 LAST SCH_REV 2.420
J 0
(4000 350);
DISPLAY 0.978723 (4000 350);
PAINT YELLOW (4000 350);
FORCEPROP 1 LAST SCH_ADDRESS3 Santa Clara, CA 95052-8119
J 0
(275 225);
DISPLAY 0.617021 (275 225);
PAINT GREEN (275 225);
FORCEPROP 1 LAST SCH_ADDRESS1 2200 Mission College Blvd.
J 0
(275 325);
DISPLAY 0.617021 (275 325);
PAINT GREEN (275 325);
FORCEPROP 1 LAST SCH_ADDRESS2 P.O. BOX 58119
J 0
(275 275);
DISPLAY 0.617021 (275 275);
PAINT GREEN (275 275);
FORCEPROP 1 LAST SCH_TITLE PVCCIO CPU1 (2 OF 2)
J 0
(-3700 250);
DISPLAY 1.212766 (-3700 250);
PAINT ORANGE (-3700 250);
FORCEPROP 1 LAST COMMENT_BODY TRUE
J 0
(4262 212);
DISPLAY 0.468085 (4262 212);
PAINT GREEN (4262 212);
DISPLAY INVISIBLE (4262 212);
FORCEPROP 2 LAST CDS_LIB mstr_symbols
J 0
(4250 200);
PAINT MONO (4250 200);
DISPLAY INVISIBLE (4250 200);
FORCEPROP 2 LAST PAGE_BORDER TRUE
J 0
(-3640 5450);
DISPLAY 0.638298 (-3640 5450);
PAINT PINK (-3640 5450);
DISPLAY INVISIBLE (-3640 5450);
FORCEPROP 2 LAST CDS_XR_PAGE_TITLE CR-214 : @BASEBOARD_FAB2_LIB.BASEBOARD_FAB2(SCH_1):PAGE214
J 0
(-3640 5450);
DISPLAY 0.638298 (-3640 5450);
PAINT PINK (-3640 5450);
DISPLAY INVISIBLE (-3640 5450);
WIRE 16 -1 (-400 1050)(-250 1050);
WIRE 16 -1 (-250 875)(-250 1050);
WIRE 16 -1 (-400 2250)(-250 2250);
WIRE 16 -1 (-250 2475)(-250 2250);
WIRE 16 -1 (3175 3425)(3175 3525);
WIRE 16 -1 (2150 2600)(2150 2575);
WIRE 16 -1 (2050 3400)(2050 3350);
WIRE 16 -1 (50 2875)(50 2775);
WIRE 16 -1 (1275 1800)(1275 1700);
WIRE 16 -1 (2425 2300)(2425 2450);
WIRE 16 -1 (2425 2450)(2900 2450);
WIRE 16 -1 (2900 2300)(2900 2450);
WIRE 16 -1 (2900 2450)(3375 2450);
WIRE 16 -1 (3375 2300)(3375 2450);
WIRE 16 -1 (3375 2500)(3375 2450);
WIRE 16 -1 (700 1975)(700 2125);
WIRE 16 -1 (700 2125)(1275 2125);
WIRE 16 -1 (1275 2000)(1275 2125);
WIRE 16 -1 (1650 2125)(1275 2125);
WIRE 16 -1 (1650 2000)(1650 2125);
WIRE 16 -1 (1650 2175)(1650 2125);
WIRE 16 -1 (700 1775)(700 1700);
WIRE 16 -1 (2425 2100)(2425 1975);
WIRE 16 -1 (2425 1975)(2900 1975);
WIRE 16 -1 (2900 2100)(2900 1975);
WIRE 16 -1 (2900 1975)(3375 1975);
WIRE 16 -1 (3375 2100)(3375 1975);
WIRE 16 -1 (3375 1975)(3375 1950);
WIRE 16 -1 (350 3625)(225 3625);
WIRE 16 -1 (225 3625)(225 2475);
WIRE 16 -1 (225 2475)(2775 2475);
WIRE 16 -1 (2775 2475)(2775 3175);
WIRE 16 -1 (2650 3175)(2775 3175);
WIRE 16 -1 (2775 3175)(3125 3175);
WIRE 16 -1 (3125 3100)(3125 3175);
WIRE 16 -1 (3575 3175)(3125 3175);
WIRE 16 -1 (3575 3100)(3575 3175);
WIRE 16 -1 (3875 3175)(3575 3175);
WIRE 16 -1 (3875 3225)(3875 3175);
WIRE 16 -1 (3875 3175)(3875 3075);
WIRE 16 -1 (3125 2775)(3575 2775);
WIRE 16 -1 (3125 2775)(3125 2900);
WIRE 16 -1 (3575 2900)(3575 2775);
WIRE 16 -1 (3875 2775)(3575 2775);
WIRE 16 -1 (3875 2875)(3875 2775);
WIRE 16 -1 (3875 2725)(3875 2775);
WIRE 16 -1 (1350 3075)(1500 3075);
WIRE 16 -1 (1500 3025)(1500 3075);
WIRE 16 -1 (1500 2975)(1500 3025);
WIRE 16 -1 (1500 3025)(1350 3025);
WIRE 16 -1 (1500 2925)(1500 2975);
WIRE 16 -1 (1500 2975)(1350 2975);
WIRE 16 -1 (1500 2850)(1500 2925);
WIRE 16 -1 (1500 2925)(1350 2925);
WIRE 16 -1 (-1425 3650)(-1425 3475);
WIRE 16 -1 (-1425 3475)(-1575 3475);
WIRE 16 -1 (-1575 3675)(-1575 3475);
WIRE 16 -1 (-1575 3475)(-2125 3475);
WIRE 16 -1 (-2125 3600)(-2125 3475);
WIRE 16 -1 (-2125 3475)(-2375 3475);
WIRE 16 -1 (-2375 3625)(-2375 3475);
WIRE 16 -1 (-2375 3475)(-2600 3475);
WIRE 16 -1 (-2600 3600)(-2600 3475);
WIRE 16 -1 (-2600 3475)(-2825 3475);
WIRE 16 -1 (-2825 3625)(-2825 3475);
WIRE 16 -1 (-2825 3475)(-3050 3475);
WIRE 16 -1 (-3050 3600)(-3050 3475);
WIRE 16 -1 (-3050 3475)(-3275 3475);
WIRE 16 -1 (-3275 3625)(-3275 3475);
WIRE 16 -1 (-3275 3425)(-3275 3475);
WIRE 16 -1 (350 3725)(275 3725);
WIRE 16 -1 (275 3725)(275 3825);
WIRE 16 -1 (275 3825)(350 3825);
WIRE 16 -1 (-900 3825)(275 3825);
WIRE 16 -1 (-900 4300)(-900 3825);
WIRE 16 -1 (-900 4300)(-1425 4300);
WIRE 16 -1 (-900 4300)(-900 4350);
WIRE 16 -1 (-1425 4300)(-1575 4300);
WIRE 16 -1 (-1425 3850)(-1425 4300);
WIRE 16 -1 (-1575 4300)(-1775 4300);
WIRE 16 -1 (-1575 3875)(-1575 4300);
WIRE 16 -1 (350 3925)(125 3925);
WIRE 16 -1 (125 3975)(125 3925);
WIRE 16 -1 (350 3975)(125 3975);
WIRE 16 -1 (125 3975)(-2375 3975);
WIRE 16 -1 (-2375 3825)(-2375 3975);
WIRE 16 -1 (-2375 3975)(-2600 3975);
WIRE 16 -1 (-2600 3800)(-2600 3975);
WIRE 16 -1 (-2600 3975)(-2825 3975);
WIRE 16 -1 (-2825 3825)(-2825 3975);
WIRE 16 -1 (-2825 3975)(-3050 3975);
WIRE 16 -1 (-3050 3800)(-3050 3975);
WIRE 16 -1 (-3050 3975)(-3275 3975);
WIRE 16 -1 (-3275 3825)(-3275 3975);
WIRE 16 -1 (-3275 4200)(-3275 3975);
WIRE 16 -1 (1650 1800)(1650 1675);
WIRE 16 -1 (2050 3600)(2050 3675);
WIRE 16 -1 (2050 3675)(2450 3675);
WIRE 16 -1 (1350 3675)(2050 3675);
FORCEPROP 2 LAST SIG_NAME A_TSENSE_PVCCIO_CPU1
J 2
(1800 3689);
DISPLAY 0.617021 (1800 3689);
PAINT ORANGE (1800 3689);
WIRE 16 -1 (1350 3675)(1350 3525);
WIRE 3 2175 (1825 3725)(2275 3725);
WIRE 3 2175 (1825 3725)(1825 3250);
WIRE 3 2175 (2275 3725)(2275 3250);
WIRE 3 2175 (1825 3250)(2275 3250);
WIRE 3 2175 (1875 2500)(2375 2500);
WIRE 3 2175 (1875 3225)(1875 2500);
WIRE 3 2175 (2375 3225)(2375 2500);
WIRE 3 2175 (1875 3225)(2375 3225);
WIRE 16 -1 (1350 3175)(2150 3175);
FORCEPROP 2 LAST SIG_NAME VR_PVCCIO_CPU1_PH1_SW
J 0
(1415 3185);
DISPLAY 0.617021 (1415 3185);
PAINT ORANGE (1415 3185);
FORCEPROP 2 LASTPROP $XRERR UNIQUE?
J 0
(1175 3185);
DISPLAY 0.638298 (1175 3185);
PAINT MONO (1175 3185);
DISPLAY INVISIBLE (1175 3185);
WIRE 16 -1 (2150 3175)(2450 3175);
WIRE 16 -1 (2150 3100)(2150 3175);
WIRE 16 -1 (2150 2850)(2150 2950);
WIRE 16 -1 (1350 3775)(1975 3775);
FORCEPROP 2 LAST SIG_NAME NC_PVCCIO_CPU1_PH1_P31
J 0
(1492 3785);
DISPLAY 0.617021 (1492 3785);
PAINT ORANGE (1492 3785);
FORCEPROP 2 LASTPROP $XRERR UNIQUE?
J 0
(2005 3775);
DISPLAY 0.638298 (2005 3775);
PAINT MONO (2005 3775);
DISPLAY INVISIBLE (2005 3775);
WIRE 3 2175 (-275 2700)(450 2700);
WIRE 3 2175 (-275 3225)(-275 2700);
WIRE 3 2175 (450 3225)(450 2700);
WIRE 3 2175 (-275 3225)(450 3225);
WIRE 16 -1 (-1675 2975)(-200 2975);
FORCEPROP 2 LAST SIG_NAME VR_PVCCIO_CPU1_PH1_PHASE
J 0
(-1660 2985);
DISPLAY 0.617021 (-1660 2985);
PAINT ORANGE (-1660 2985);
FORCEPROP 2 LASTPROP $XRERR UNIQUE?
J 0
(-1900 2985);
DISPLAY 0.638298 (-1900 2985);
PAINT MONO (-1900 2985);
DISPLAY INVISIBLE (-1900 2985);
WIRE 16 -1 (-1675 2975)(-1675 3025);
WIRE 16 -1 (-200 2975)(-200 3125);
WIRE 16 -1 (-200 3125)(350 3125);
WIRE 16 -1 (-850 3250)(-200 3250);
FORCEPROP 0 LAST SIG_NAME VR_PVCCIO_CPU1_PH1_BOOT_R
J 0
(-735 3260);
DISPLAY 0.617021 (-735 3260);
PAINT ORANGE (-735 3260);
FORCEPROP 2 LASTPROP $XRERR UNIQUE?
J 0
(-975 3260);
DISPLAY 0.638298 (-975 3260);
PAINT MONO (-975 3260);
DISPLAY INVISIBLE (-975 3260);
WIRE 16 -1 (-200 3250)(-200 3175);
WIRE 16 -1 (-200 3175)(350 3175);
WIRE 16 -1 (-600 2250)(-750 2250);
WIRE 16 -1 (-750 2250)(-750 1750);
WIRE 16 -1 (-100 1750)(-750 1750);
FORCEPROP 2 LAST SIG_NAME VSENSE_PVCCIO_CPU1_AVSP
J 0
(-725 1763);
DISPLAY 0.617021 (-725 1763);
PAINT ORANGE (-725 1763);
WIRE 16 -1 (-750 1750)(-975 1750);
WIRE 3 2175 (-1125 3325)(-750 3325);
WIRE 3 2175 (-1125 3325)(-1125 3075);
WIRE 3 2175 (-750 3325)(-750 3075);
WIRE 3 2175 (-1125 3075)(-750 3075);
WIRE 16 -1 (-1050 3250)(-1675 3250);
FORCEPROP 0 LAST SIG_NAME VR_PVCCIO_CPU1_PH1_BOOT
J 0
(-1660 3260);
DISPLAY 0.617021 (-1660 3260);
PAINT ORANGE (-1660 3260);
FORCEPROP 2 LASTPROP $XRERR UNIQUE?
J 0
(-1900 3260);
DISPLAY 0.638298 (-1900 3260);
PAINT MONO (-1900 3260);
DISPLAY INVISIBLE (-1900 3260);
WIRE 16 -1 (-1675 3250)(-1675 3225);
WIRE 16 2175 (-1925 3325)(-1150 3325);
WIRE 16 2175 (-1925 3325)(-1925 2925);
WIRE 16 2175 (-1150 3325)(-1150 2925);
WIRE 16 2175 (-1925 2925)(-1150 2925);
WIRE 16 -1 (-75 1300)(-750 1300);
FORCEPROP 2 LAST SIG_NAME VSENSE_PVCCIO_CPU1_AVSN
J 0
(-738 1313);
DISPLAY 0.617021 (-738 1313);
PAINT ORANGE (-738 1313);
WIRE 16 -1 (-750 1050)(-750 1300);
WIRE 16 -1 (-975 1300)(-750 1300);
WIRE 16 -1 (-600 1050)(-750 1050);
WIRE 16 -1 (-2500 3375)(350 3375);
FORCEPROP 2 LAST SIG_NAME VR_PVCCIO_CPU1_PWM1
J 0
(-2475 3399);
DISPLAY 0.617021 (-2475 3399);
PAINT ORANGE (-2475 3399);
WIRE 16 -1 (1350 4025)(2600 4025);
FORCEPROP 2 LAST SIG_NAME ISENSE_PVCCIO_CPU1_PH1_IMON
J 2
(2375 4039);
DISPLAY 0.617021 (2375 4039);
PAINT ORANGE (2375 4039);
WIRE 16 -1 (-2125 4025)(350 4025);
FORCEPROP 2 LAST SIG_NAME VR_PVCCIO_CPU1_PH1_VCIN
J 0
(-485 4035);
DISPLAY 0.617021 (-485 4035);
PAINT ORANGE (-485 4035);
FORCEPROP 2 LASTPROP $XRERR UNIQUE?
J 0
(-725 4035);
DISPLAY 0.638298 (-725 4035);
PAINT MONO (-725 4035);
DISPLAY INVISIBLE (-725 4035);
WIRE 16 -1 (-2125 4025)(-2125 4300);
WIRE 16 -1 (-2125 3800)(-2125 4025);
WIRE 16 -1 (-2125 4300)(-1975 4300);
WIRE 16 2175 (-1900 3525)(-1150 3525);
WIRE 16 2175 (-1900 3925)(-1900 3525);
WIRE 16 2175 (-1150 3925)(-1150 3525);
WIRE 16 2175 (-1900 3925)(-1150 3925);
WIRE 16 -1 (350 3275)(50 3275);
WIRE 16 -1 (50 3275)(50 4375);
WIRE 16 -1 (50 3075)(50 3275);
WIRE 16 -1 (50 4375)(2575 4375);
FORCEPROP 2 LAST SIG_NAME VR_PVCCIO_CPU1_AIREF1
J 0
(1220 4379);
DISPLAY 0.617021 (1220 4379);
PAINT ORANGE (1220 4379);
WIRE 16 2175 (-800 1050)(-800 1900);
WIRE 16 2175 (-1450 1050)(-800 1050);
WIRE 16 2175 (-800 1900)(-1450 1900);
WIRE 16 2175 (-1450 1900)(-1450 1050);
WIRE 16 -1 (1350 3825)(3175 3825);
FORCEPROP 0 LAST SIG_NAME VR_PVCCIO_CPU1_OCSET
J 0
(1440 3835);
DISPLAY 0.617021 (1440 3835);
PAINT ORANGE (1440 3835);
FORCEPROP 2 LASTPROP $XRERR UNIQUE?
J 0
(1200 3835);
DISPLAY 0.638298 (1200 3835);
PAINT MONO (1200 3835);
DISPLAY INVISIBLE (1200 3835);
WIRE 16 -1 (3175 3725)(3175 3825);
WIRE 16 -1 (350 3475)(-575 3475);
FORCEPROP 0 LAST SIG_NAME TP_PVCCIO_CPU1_GL_0
J 0
(-560 3485);
DISPLAY 0.617021 (-560 3485);
PAINT ORANGE (-560 3485);
FORCEPROP 2 LASTPROP $XRERR UNIQUE?
J 0
(-815 3475);
DISPLAY 0.638298 (-815 3475);
PAINT MONO (-815 3475);
DISPLAY INVISIBLE (-815 3475);
WIRE 16 -1 (350 3525)(-550 3525);
FORCEPROP 0 LAST SIG_NAME TP_PVCCIO_CPU1_GL_1
J 0
(-535 3535);
DISPLAY 0.617021 (-535 3535);
PAINT ORANGE (-535 3535);
FORCEPROP 2 LASTPROP $XRERR UNIQUE?
J 0
(-790 3525);
DISPLAY 0.638298 (-790 3525);
PAINT MONO (-790 3525);
DISPLAY INVISIBLE (-790 3525);
WIRE 16 -1 (-2275 1750)(-2275 1550);
WIRE 16 -1 (-2275 1750)(-3000 1750);
FORCEPROP 2 LAST SIG_NAME VSENSE_PVCCIO_CPU1_SKT_VSEN
J 0
(-3004 1758);
DISPLAY 0.617021 (-3004 1758);
PAINT ORANGE (-3004 1758);
WIRE 16 -1 (-2275 1550)(-1875 1550);
WIRE 16 -1 (-1875 1550)(-1875 1750);
WIRE 16 -1 (-1875 1750)(-1725 1750);
WIRE 16 -1 (-1725 1750)(-1275 1750);
WIRE 16 -1 (-1725 1675)(-1725 1750);
WIRE 16 -1 (-3000 1300)(-2275 1300);
FORCEPROP 2 LAST SIG_NAME VSENSE_PVCCIO_CPU1_SKT_VRTN
J 0
(-3003 1325);
DISPLAY 0.617021 (-3003 1325);
PAINT ORANGE (-3003 1325);
WIRE 16 -1 (-2275 1300)(-2275 1500);
WIRE 16 -1 (-2275 1500)(-1875 1500);
WIRE 16 -1 (-1875 1500)(-1875 1300);
WIRE 16 -1 (-1875 1300)(-1725 1300);
WIRE 16 -1 (-1275 1300)(-1725 1300);
WIRE 16 -1 (-1725 1475)(-1725 1300);
WIRE 16 2175 (-1925 1300)(-1925 1750);
WIRE 16 2175 (-2250 1300)(-1925 1300);
WIRE 16 2175 (-1925 1750)(-2250 1750);
WIRE 16 2175 (-2250 1750)(-2250 1300);
WIRE 16 682 (-3525 2725)(-2625 2725);
WIRE 16 682 (-3525 2000)(-3525 2725);
WIRE 16 682 (-2625 2725)(-2625 2000);
WIRE 16 682 (-2625 2000)(-3525 2000);
DOT 1 (2150 3175);
DOT 1 (50 3275);
DOT 1 (2050 3675);
DOT 1 (1275 2125);
DOT 1 (1650 2125);
DOT 1 (-3275 3475);
DOT 1 (-3275 3975);
DOT 1 (-3050 3475);
DOT 1 (-2825 3475);
DOT 1 (-2600 3475);
DOT 1 (-3050 3975);
DOT 1 (-2825 3975);
DOT 1 (-2600 3975);
DOT 1 (-2375 3475);
DOT 1 (-2125 3475);
DOT 1 (-2375 3975);
DOT 1 (-2125 4025);
DOT 1 (-1725 1300);
DOT 1 (-1725 1750);
DOT 1 (-750 1300);
DOT 1 (-750 1750);
DOT 1 (-1575 3475);
DOT 1 (-1575 4300);
DOT 1 (-1425 4300);
DOT 1 (-900 4300);
DOT 1 (125 3975);
DOT 1 (275 3825);
DOT 1 (1500 2925);
DOT 1 (1500 2975);
DOT 1 (1500 3025);
DOT 1 (2900 1975);
DOT 1 (3375 1975);
DOT 1 (2900 2450);
DOT 1 (3375 2450);
DOT 1 (3575 2775);
DOT 1 (3875 2775);
DOT 1 (3125 3175);
DOT 1 (3575 3175);
DOT 1 (3875 3175);
DOT 1 (2775 3175);
FORCENOTE
TOTAL TOL = 1.057VMAX/0.937VMIN
(-3500 2325) 0;
DISPLAY LEFT (-3500 2325);
DISPLAY 0.808511 (-3500 2325);
PAINT PURPLE (-3500 2325);
FORCENOTE
VOUT=1.0V (TYP) SVID
(-3500 2475) 0;
DISPLAY LEFT (-3500 2475);
DISPLAY 0.808511 (-3500 2475);
PAINT PURPLE (-3500 2475);
FORCENOTE
BOM_COST = PROC_VRD_PVCCIO_CPU1
(-3675 400) 0;
DISPLAY LEFT (-3675 400);
DISPLAY 1.021277 (-3675 400);
PAINT PURPLE (-3675 400);
FORCENOTE
ROOM = PVCCIO_CPU1
(-3675 475) 0;
DISPLAY LEFT (-3675 475);
DISPLAY 1.021277 (-3675 475);
PAINT PURPLE (-3675 475);
FORCENOTE
SOCKET SIDE
(-3093 1526) 0;
DISPLAY LEFT (-3093 1526);
DISPLAY 1.021277 (-3093 1526);
PAINT PURPLE (-3093 1526);
FORCENOTE
VBOOT=1.0V 
(-3500 2025) 0;
DISPLAY LEFT (-3500 2025);
DISPLAY 0.808511 (-3500 2025);
PAINT PURPLE (-3500 2025);
FORCENOTE
IOUT DI/DT =22 A/US
(-3500 2125) 0;
DISPLAY LEFT (-3500 2125);
DISPLAY 0.808511 (-3500 2125);
PAINT PURPLE (-3500 2125);
FORCENOTE
IOUT STEP=14APP
(-3500 2175) 0;
DISPLAY LEFT (-3500 2175);
DISPLAY 0.808511 (-3500 2175);
PAINT PURPLE (-3500 2175);
FORCENOTE
RIPPLE = +/- 10MV
(-3500 2425) 0;
DISPLAY LEFT (-3500 2425);
DISPLAY 0.808511 (-3500 2425);
PAINT PURPLE (-3500 2425);
FORCENOTE
DC TOL = +/-5MV
(-3500 2375) 0;
DISPLAY LEFT (-3500 2375);
DISPLAY 0.808511 (-3500 2375);
PAINT PURPLE (-3500 2375);
FORCENOTE
IOUT TDC=11A
(-3500 2275) 0;
DISPLAY LEFT (-3500 2275);
DISPLAY 0.808511 (-3500 2275);
PAINT PURPLE (-3500 2275);
FORCENOTE
IOUT PK= 19A
(-3500 2225) 0;
DISPLAY LEFT (-3500 2225);
DISPLAY 0.808511 (-3500 2225);
PAINT PURPLE (-3500 2225);
FORCENOTE
SW FREQ=641 KHZ 
(-3500 2075) 0;
DISPLAY LEFT (-3500 2075);
DISPLAY 0.808511 (-3500 2075);
PAINT PURPLE (-3500 2075);
FORCENOTE
ROUTE AS DIFF PAIR
(-2503 1174) 0;
DISPLAY LEFT (-2503 1174);
DISPLAY 1.021277 (-2503 1174);
PAINT PURPLE (-2503 1174);
FORCENOTE
5MIL SPACING
(-2513 1034) 0;
DISPLAY LEFT (-2513 1034);
DISPLAY 1.021277 (-2513 1034);
PAINT PURPLE (-2513 1034);
FORCENOTE
5MIL WIDTH
(-2513 1109) 0;
DISPLAY LEFT (-2513 1109);
DISPLAY 1.021277 (-2513 1109);
PAINT PURPLE (-2513 1109);
FORCENOTE
SPOF
(-1134 1925) 0;
DISPLAY LEFT (-1134 1925);
DISPLAY 1.340426 (-1134 1925);
PAINT PURPLE (-1134 1925);
FORCENOTE
PLACE ON TOP
(-1905 3450) 0;
DISPLAY LEFT (-1905 3450);
DISPLAY 1.553191 (-1905 3450);
PAINT PURPLE (-1905 3450);
FORCENOTE
SPOF
(-1704 2776) 0;
DISPLAY LEFT (-1704 2776);
DISPLAY 2.340426 (-1704 2776);
PAINT PURPLE (-1704 2776);
FORCENOTE
VR CONTROLLER SIDE
(-625 1498) 0;
DISPLAY LEFT (-625 1498);
DISPLAY 1.021277 (-625 1498);
PAINT PURPLE (-625 1498);
FORCENOTE
ROOM= PVCCIO_CPU1
(-1873 2606) 0;
DISPLAY LEFT (-1873 2606);
DISPLAY 1.595745 (-1873 2606);
PAINT PURPLE (-1873 2606);
FORCENOTE
TP FAB1 CO-LAY WITH TI PARTS 11/16
(-1200 2850) 0;
DISPLAY LEFT (-1200 2850);
DISPLAY 0.851064 (-1200 2850);
PAINT RED (-1200 2850);
FORCENOTE
TP FAB1 CO-LAY WITH TI PARTS 11/16
(2275 3325) 0;
DISPLAY LEFT (2275 3325);
DISPLAY 0.851064 (2275 3325);
PAINT RED (2275 3325);
FORCENOTE
TP FAB1 3.01 OHM NEED CHANGE TO 2.2 OHM BUT WAIT FOR SYMBOL
(2375 2650) 0;
DISPLAY LEFT (2375 2650);
DISPLAY 0.851064 (2375 2650);
PAINT RED (2375 2650);
FORCENOTE
TP FAB1 CO-LAY WITH TI PARTS 11/16
(2375 2700) 0;
DISPLAY LEFT (2375 2700);
DISPLAY 0.851064 (2375 2700);
PAINT RED (2375 2700);
QUIT
